(kicad_sch
	(version 20250114)
	(generator "eeschema")
	(generator_version "9.0")
	(paper "A3")
	(title_block
		(title "Kintex 410T devboard")
		(date "2024-04-03")
		(rev "1.1.2")
	)
	(text "Supervisor MCU"
		(exclude_from_sim no)
		(at 12.7 16.51 0)
		(effects
			(font
				(size 1.27 1.27)
				(thickness 0.4)
				(bold yes)
			)
			(justify left bottom)
		)
	)
	(junction
		(at 147.32 165.1)
		(diameter 0)
		(color 0 0 0 0)
	)
	(junction
		(at 147.32 160.02)
		(diameter 0)
		(color 0 0 0 0)
	)
	(junction
		(at 129.54 121.92)
		(diameter 0)
		(color 0 0 0 0)
	)
	(junction
		(at 68.58 96.52)
		(diameter 0)
		(color 0 0 0 0)
	)
	(junction
		(at 147.32 157.48)
		(diameter 0)
		(color 0 0 0 0)
	)
	(junction
		(at 224.79 96.52)
		(diameter 0)
		(color 0 0 0 0)
	)
	(junction
		(at 129.54 119.38)
		(diameter 0)
		(color 0 0 0 0)
	)
	(junction
		(at 201.93 96.52)
		(diameter 0)
		(color 0 0 0 0)
	)
	(junction
		(at 129.54 124.46)
		(diameter 0)
		(color 0 0 0 0)
	)
	(junction
		(at 147.32 162.56)
		(diameter 0)
		(color 0 0 0 0)
	)
	(junction
		(at 129.54 116.84)
		(diameter 0)
		(color 0 0 0 0)
	)
	(junction
		(at 64.77 96.52)
		(diameter 0)
		(color 0 0 0 0)
	)
	(junction
		(at 280.67 116.84)
		(diameter 0)
		(color 0 0 0 0)
	)
	(no_connect
		(at 93.98 152.4)
	)
	(no_connect
		(at 93.98 127)
	)
	(no_connect
		(at 259.08 116.84)
	)
	(no_connect
		(at 179.07 124.46)
	)
	(no_connect
		(at 104.14 127)
	)
	(no_connect
		(at 248.92 119.38)
	)
	(no_connect
		(at 259.08 119.38)
	)
	(no_connect
		(at 179.07 114.3)
	)
	(no_connect
		(at 168.91 114.3)
	)
	(no_connect
		(at 248.92 116.84)
	)
	(bus_entry
		(at 361.95 151.13)
		(size -1.27 1.27)
		(stroke
			(width 0)
			(type default)
		)
	)
	(bus_entry
		(at 201.93 130.81)
		(size -1.27 1.27)
		(stroke
			(width 0)
			(type default)
		)
	)
	(bus_entry
		(at 68.58 163.83)
		(size 1.27 1.27)
		(stroke
			(width 0)
			(type default)
		)
	)
	(bus_entry
		(at 68.58 153.67)
		(size 1.27 1.27)
		(stroke
			(width 0)
			(type default)
		)
	)
	(bus_entry
		(at 361.95 163.83)
		(size -1.27 1.27)
		(stroke
			(width 0)
			(type default)
		)
	)
	(bus_entry
		(at 201.93 115.57)
		(size -1.27 1.27)
		(stroke
			(width 0)
			(type default)
		)
	)
	(bus_entry
		(at 68.58 135.89)
		(size 1.27 1.27)
		(stroke
			(width 0)
			(type default)
		)
	)
	(bus_entry
		(at 68.58 148.59)
		(size 1.27 1.27)
		(stroke
			(width 0)
			(type default)
		)
	)
	(bus_entry
		(at 201.93 140.97)
		(size -1.27 1.27)
		(stroke
			(width 0)
			(type default)
		)
	)
	(bus_entry
		(at 361.95 133.35)
		(size -1.27 1.27)
		(stroke
			(width 0)
			(type default)
		)
	)
	(bus_entry
		(at 361.95 120.65)
		(size -1.27 1.27)
		(stroke
			(width 0)
			(type default)
		)
	)
	(bus_entry
		(at 361.95 158.75)
		(size -1.27 1.27)
		(stroke
			(width 0)
			(type default)
		)
	)
	(bus_entry
		(at 224.79 158.75)
		(size 1.27 1.27)
		(stroke
			(width 0)
			(type default)
		)
	)
	(bus_entry
		(at 201.93 151.13)
		(size -1.27 1.27)
		(stroke
			(width 0)
			(type default)
		)
	)
	(bus_entry
		(at 361.95 148.59)
		(size -1.27 1.27)
		(stroke
			(width 0)
			(type default)
		)
	)
	(bus_entry
		(at 224.79 146.05)
		(size 1.27 1.27)
		(stroke
			(width 0)
			(type default)
		)
	)
	(bus_entry
		(at 201.93 120.65)
		(size -1.27 1.27)
		(stroke
			(width 0)
			(type default)
		)
	)
	(bus_entry
		(at 201.93 138.43)
		(size -1.27 1.27)
		(stroke
			(width 0)
			(type default)
		)
	)
	(bus_entry
		(at 361.95 156.21)
		(size -1.27 1.27)
		(stroke
			(width 0)
			(type default)
		)
	)
	(bus_entry
		(at 361.95 135.89)
		(size -1.27 1.27)
		(stroke
			(width 0)
			(type default)
		)
	)
	(bus_entry
		(at 224.79 130.81)
		(size 1.27 1.27)
		(stroke
			(width 0)
			(type default)
		)
	)
	(bus_entry
		(at 68.58 158.75)
		(size 1.27 1.27)
		(stroke
			(width 0)
			(type default)
		)
	)
	(bus_entry
		(at 68.58 128.27)
		(size 1.27 1.27)
		(stroke
			(width 0)
			(type default)
		)
	)
	(bus_entry
		(at 224.79 125.73)
		(size 1.27 1.27)
		(stroke
			(width 0)
			(type default)
		)
	)
	(bus_entry
		(at 68.58 140.97)
		(size 1.27 1.27)
		(stroke
			(width 0)
			(type default)
		)
	)
	(bus_entry
		(at 224.79 133.35)
		(size 1.27 1.27)
		(stroke
			(width 0)
			(type default)
		)
	)
	(bus_entry
		(at 361.95 138.43)
		(size -1.27 1.27)
		(stroke
			(width 0)
			(type default)
		)
	)
	(bus_entry
		(at 201.93 146.05)
		(size -1.27 1.27)
		(stroke
			(width 0)
			(type default)
		)
	)
	(bus_entry
		(at 224.79 163.83)
		(size 1.27 1.27)
		(stroke
			(width 0)
			(type default)
		)
	)
	(bus_entry
		(at 201.93 143.51)
		(size -1.27 1.27)
		(stroke
			(width 0)
			(type default)
		)
	)
	(bus_entry
		(at 224.79 151.13)
		(size 1.27 1.27)
		(stroke
			(width 0)
			(type default)
		)
	)
	(bus_entry
		(at 361.95 123.19)
		(size -1.27 1.27)
		(stroke
			(width 0)
			(type default)
		)
	)
	(bus_entry
		(at 224.79 143.51)
		(size 1.27 1.27)
		(stroke
			(width 0)
			(type default)
		)
	)
	(bus_entry
		(at 224.79 138.43)
		(size 1.27 1.27)
		(stroke
			(width 0)
			(type default)
		)
	)
	(bus_entry
		(at 68.58 133.35)
		(size 1.27 1.27)
		(stroke
			(width 0)
			(type default)
		)
	)
	(bus_entry
		(at 224.79 156.21)
		(size 1.27 1.27)
		(stroke
			(width 0)
			(type default)
		)
	)
	(bus_entry
		(at 201.93 135.89)
		(size -1.27 1.27)
		(stroke
			(width 0)
			(type default)
		)
	)
	(bus_entry
		(at 361.95 115.57)
		(size -1.27 1.27)
		(stroke
			(width 0)
			(type default)
		)
	)
	(bus_entry
		(at 201.93 148.59)
		(size -1.27 1.27)
		(stroke
			(width 0)
			(type default)
		)
	)
	(bus_entry
		(at 34.29 102.87)
		(size 1.27 -1.27)
		(stroke
			(width 0)
			(type default)
		)
	)
	(bus_entry
		(at 361.95 153.67)
		(size -1.27 1.27)
		(stroke
			(width 0)
			(type default)
		)
	)
	(bus_entry
		(at 361.95 130.81)
		(size -1.27 1.27)
		(stroke
			(width 0)
			(type default)
		)
	)
	(bus_entry
		(at 68.58 138.43)
		(size 1.27 1.27)
		(stroke
			(width 0)
			(type default)
		)
	)
	(bus_entry
		(at 224.79 128.27)
		(size 1.27 1.27)
		(stroke
			(width 0)
			(type default)
		)
	)
	(bus_entry
		(at 361.95 143.51)
		(size -1.27 1.27)
		(stroke
			(width 0)
			(type default)
		)
	)
	(bus_entry
		(at 224.79 161.29)
		(size 1.27 1.27)
		(stroke
			(width 0)
			(type default)
		)
	)
	(bus_entry
		(at 361.95 118.11)
		(size -1.27 1.27)
		(stroke
			(width 0)
			(type default)
		)
	)
	(bus_entry
		(at 64.77 102.87)
		(size -1.27 1.27)
		(stroke
			(width 0)
			(type default)
		)
	)
	(bus_entry
		(at 361.95 125.73)
		(size -1.27 1.27)
		(stroke
			(width 0)
			(type default)
		)
	)
	(bus_entry
		(at 201.93 125.73)
		(size -1.27 1.27)
		(stroke
			(width 0)
			(type default)
		)
	)
	(bus_entry
		(at 68.58 130.81)
		(size 1.27 1.27)
		(stroke
			(width 0)
			(type default)
		)
	)
	(bus_entry
		(at 34.29 105.41)
		(size 1.27 -1.27)
		(stroke
			(width 0)
			(type default)
		)
	)
	(bus_entry
		(at 224.79 123.19)
		(size 1.27 1.27)
		(stroke
			(width 0)
			(type default)
		)
	)
	(bus_entry
		(at 361.95 146.05)
		(size -1.27 1.27)
		(stroke
			(width 0)
			(type default)
		)
	)
	(bus_entry
		(at 361.95 161.29)
		(size -1.27 1.27)
		(stroke
			(width 0)
			(type default)
		)
	)
	(bus_entry
		(at 224.79 140.97)
		(size 1.27 1.27)
		(stroke
			(width 0)
			(type default)
		)
	)
	(bus_entry
		(at 68.58 146.05)
		(size 1.27 1.27)
		(stroke
			(width 0)
			(type default)
		)
	)
	(bus_entry
		(at 361.95 140.97)
		(size -1.27 1.27)
		(stroke
			(width 0)
			(type default)
		)
	)
	(bus_entry
		(at 224.79 148.59)
		(size 1.27 1.27)
		(stroke
			(width 0)
			(type default)
		)
	)
	(bus_entry
		(at 68.58 156.21)
		(size 1.27 1.27)
		(stroke
			(width 0)
			(type default)
		)
	)
	(bus_entry
		(at 224.79 135.89)
		(size 1.27 1.27)
		(stroke
			(width 0)
			(type default)
		)
	)
	(bus_entry
		(at 64.77 100.33)
		(size -1.27 1.27)
		(stroke
			(width 0)
			(type default)
		)
	)
	(bus_entry
		(at 361.95 128.27)
		(size -1.27 1.27)
		(stroke
			(width 0)
			(type default)
		)
	)
	(bus_entry
		(at 224.79 120.65)
		(size 1.27 1.27)
		(stroke
			(width 0)
			(type default)
		)
	)
	(bus_entry
		(at 68.58 143.51)
		(size 1.27 1.27)
		(stroke
			(width 0)
			(type default)
		)
	)
	(bus_entry
		(at 201.93 118.11)
		(size -1.27 1.27)
		(stroke
			(width 0)
			(type default)
		)
	)
	(bus_entry
		(at 68.58 161.29)
		(size 1.27 1.27)
		(stroke
			(width 0)
			(type default)
		)
	)
	(bus_entry
		(at 201.93 128.27)
		(size -1.27 1.27)
		(stroke
			(width 0)
			(type default)
		)
	)
	(bus_entry
		(at 224.79 153.67)
		(size 1.27 1.27)
		(stroke
			(width 0)
			(type default)
		)
	)
	(bus_entry
		(at 201.93 133.35)
		(size -1.27 1.27)
		(stroke
			(width 0)
			(type default)
		)
	)
	(wire
		(pts
			(xy 143.51 139.7) (xy 168.91 139.7)
		)
		(stroke
			(width 0)
			(type default)
		)
	)
	(wire
		(pts
			(xy 280.67 119.38) (xy 283.21 119.38)
		)
		(stroke
			(width 0)
			(type default)
		)
	)
	(bus
		(pts
			(xy 68.58 161.29) (xy 68.58 163.83)
		)
		(stroke
			(width 0)
			(type default)
		)
	)
	(bus
		(pts
			(xy 34.29 105.41) (xy 34.29 102.87)
		)
		(stroke
			(width 0)
			(type default)
		)
	)
	(wire
		(pts
			(xy 259.08 132.08) (xy 283.21 132.08)
		)
		(stroke
			(width 0)
			(type default)
		)
	)
	(bus
		(pts
			(xy 68.58 96.52) (xy 201.93 96.52)
		)
		(stroke
			(width 0)
			(type default)
		)
	)
	(wire
		(pts
			(xy 143.51 152.4) (xy 168.91 152.4)
		)
		(stroke
			(width 0)
			(type default)
		)
	)
	(wire
		(pts
			(xy 200.66 142.24) (xy 179.07 142.24)
		)
		(stroke
			(width 0)
			(type default)
		)
	)
	(bus
		(pts
			(xy 361.95 138.43) (xy 361.95 135.89)
		)
		(stroke
			(width 0)
			(type default)
		)
	)
	(wire
		(pts
			(xy 69.85 129.54) (xy 93.98 129.54)
		)
		(stroke
			(width 0)
			(type default)
		)
	)
	(wire
		(pts
			(xy 226.06 121.92) (xy 248.92 121.92)
		)
		(stroke
			(width 0)
			(type default)
		)
	)
	(wire
		(pts
			(xy 69.85 149.86) (xy 93.98 149.86)
		)
		(stroke
			(width 0)
			(type default)
		)
	)
	(wire
		(pts
			(xy 259.08 139.7) (xy 283.21 139.7)
		)
		(stroke
			(width 0)
			(type default)
		)
	)
	(wire
		(pts
			(xy 69.85 165.1) (xy 93.98 165.1)
		)
		(stroke
			(width 0)
			(type default)
		)
	)
	(bus
		(pts
			(xy 361.95 97.79) (xy 361.95 115.57)
		)
		(stroke
			(width 0)
			(type default)
		)
	)
	(wire
		(pts
			(xy 104.14 142.24) (xy 132.08 142.24)
		)
		(stroke
			(width 0)
			(type default)
		)
	)
	(wire
		(pts
			(xy 332.74 121.92) (xy 360.68 121.92)
		)
		(stroke
			(width 0)
			(type default)
		)
	)
	(wire
		(pts
			(xy 332.74 127) (xy 360.68 127)
		)
		(stroke
			(width 0)
			(type default)
		)
	)
	(bus
		(pts
			(xy 361.95 120.65) (xy 361.95 118.11)
		)
		(stroke
			(width 0)
			(type default)
		)
	)
	(wire
		(pts
			(xy 226.06 127) (xy 248.92 127)
		)
		(stroke
			(width 0)
			(type default)
		)
	)
	(bus
		(pts
			(xy 361.95 118.11) (xy 361.95 115.57)
		)
		(stroke
			(width 0)
			(type default)
		)
	)
	(bus
		(pts
			(xy 68.58 96.52) (xy 68.58 128.27)
		)
		(stroke
			(width 0)
			(type default)
		)
	)
	(wire
		(pts
			(xy 35.56 104.14) (xy 43.18 104.14)
		)
		(stroke
			(width 0)
			(type default)
		)
	)
	(wire
		(pts
			(xy 143.51 124.46) (xy 168.91 124.46)
		)
		(stroke
			(width 0)
			(type default)
		)
	)
	(bus
		(pts
			(xy 361.95 161.29) (xy 361.95 158.75)
		)
		(stroke
			(width 0)
			(type default)
		)
	)
	(wire
		(pts
			(xy 104.14 149.86) (xy 132.08 149.86)
		)
		(stroke
			(width 0)
			(type default)
		)
	)
	(wire
		(pts
			(xy 143.51 149.86) (xy 168.91 149.86)
		)
		(stroke
			(width 0)
			(type default)
		)
	)
	(wire
		(pts
			(xy 125.73 116.84) (xy 125.73 118.11)
		)
		(stroke
			(width 0)
			(type default)
		)
	)
	(bus
		(pts
			(xy 68.58 146.05) (xy 68.58 148.59)
		)
		(stroke
			(width 0)
			(type default)
		)
	)
	(bus
		(pts
			(xy 68.58 128.27) (xy 68.58 130.81)
		)
		(stroke
			(width 0)
			(type default)
		)
	)
	(bus
		(pts
			(xy 64.77 100.33) (xy 64.77 102.87)
		)
		(stroke
			(width 0)
			(type default)
		)
	)
	(bus
		(pts
			(xy 224.79 138.43) (xy 224.79 140.97)
		)
		(stroke
			(width 0)
			(type default)
		)
	)
	(wire
		(pts
			(xy 143.51 121.92) (xy 168.91 121.92)
		)
		(stroke
			(width 0)
			(type default)
		)
	)
	(wire
		(pts
			(xy 129.54 119.38) (xy 132.08 119.38)
		)
		(stroke
			(width 0)
			(type default)
		)
	)
	(wire
		(pts
			(xy 69.85 160.02) (xy 93.98 160.02)
		)
		(stroke
			(width 0)
			(type default)
		)
	)
	(wire
		(pts
			(xy 259.08 160.02) (xy 283.21 160.02)
		)
		(stroke
			(width 0)
			(type default)
		)
	)
	(wire
		(pts
			(xy 332.74 134.62) (xy 360.68 134.62)
		)
		(stroke
			(width 0)
			(type default)
		)
	)
	(bus
		(pts
			(xy 34.29 106.68) (xy 33.02 107.95)
		)
		(stroke
			(width 0)
			(type default)
		)
	)
	(bus
		(pts
			(xy 201.93 143.51) (xy 201.93 146.05)
		)
		(stroke
			(width 0)
			(type default)
		)
	)
	(wire
		(pts
			(xy 332.74 160.02) (xy 360.68 160.02)
		)
		(stroke
			(width 0)
			(type default)
		)
	)
	(wire
		(pts
			(xy 104.14 137.16) (xy 132.08 137.16)
		)
		(stroke
			(width 0)
			(type default)
		)
	)
	(wire
		(pts
			(xy 200.66 144.78) (xy 179.07 144.78)
		)
		(stroke
			(width 0)
			(type default)
		)
	)
	(wire
		(pts
			(xy 143.51 162.56) (xy 147.32 162.56)
		)
		(stroke
			(width 0)
			(type default)
		)
	)
	(wire
		(pts
			(xy 104.14 152.4) (xy 132.08 152.4)
		)
		(stroke
			(width 0)
			(type default)
		)
	)
	(bus
		(pts
			(xy 201.93 148.59) (xy 201.93 151.13)
		)
		(stroke
			(width 0)
			(type default)
		)
	)
	(bus
		(pts
			(xy 224.79 146.05) (xy 224.79 148.59)
		)
		(stroke
			(width 0)
			(type default)
		)
	)
	(wire
		(pts
			(xy 104.14 129.54) (xy 132.08 129.54)
		)
		(stroke
			(width 0)
			(type default)
		)
	)
	(wire
		(pts
			(xy 129.54 124.46) (xy 132.08 124.46)
		)
		(stroke
			(width 0)
			(type default)
		)
	)
	(wire
		(pts
			(xy 294.64 162.56) (xy 322.58 162.56)
		)
		(stroke
			(width 0)
			(type default)
		)
	)
	(wire
		(pts
			(xy 294.64 124.46) (xy 322.58 124.46)
		)
		(stroke
			(width 0)
			(type default)
		)
	)
	(bus
		(pts
			(xy 68.58 158.75) (xy 68.58 161.29)
		)
		(stroke
			(width 0)
			(type default)
		)
	)
	(bus
		(pts
			(xy 361.95 123.19) (xy 361.95 125.73)
		)
		(stroke
			(width 0)
			(type default)
		)
	)
	(wire
		(pts
			(xy 226.06 157.48) (xy 248.92 157.48)
		)
		(stroke
			(width 0)
			(type default)
		)
	)
	(wire
		(pts
			(xy 259.08 149.86) (xy 283.21 149.86)
		)
		(stroke
			(width 0)
			(type default)
		)
	)
	(bus
		(pts
			(xy 224.79 158.75) (xy 224.79 161.29)
		)
		(stroke
			(width 0)
			(type default)
		)
	)
	(bus
		(pts
			(xy 361.95 153.67) (xy 361.95 151.13)
		)
		(stroke
			(width 0)
			(type default)
		)
	)
	(bus
		(pts
			(xy 224.79 96.52) (xy 224.79 120.65)
		)
		(stroke
			(width 0)
			(type default)
		)
	)
	(bus
		(pts
			(xy 34.29 105.41) (xy 34.29 106.68)
		)
		(stroke
			(width 0)
			(type default)
		)
	)
	(wire
		(pts
			(xy 294.64 129.54) (xy 322.58 129.54)
		)
		(stroke
			(width 0)
			(type default)
		)
	)
	(wire
		(pts
			(xy 129.54 121.92) (xy 129.54 124.46)
		)
		(stroke
			(width 0)
			(type default)
		)
	)
	(wire
		(pts
			(xy 143.51 147.32) (xy 168.91 147.32)
		)
		(stroke
			(width 0)
			(type default)
		)
	)
	(bus
		(pts
			(xy 201.93 138.43) (xy 201.93 140.97)
		)
		(stroke
			(width 0)
			(type default)
		)
	)
	(bus
		(pts
			(xy 224.79 96.52) (xy 360.68 96.52)
		)
		(stroke
			(width 0)
			(type default)
		)
	)
	(bus
		(pts
			(xy 224.79 140.97) (xy 224.79 143.51)
		)
		(stroke
			(width 0)
			(type default)
		)
	)
	(wire
		(pts
			(xy 129.54 121.92) (xy 132.08 121.92)
		)
		(stroke
			(width 0)
			(type default)
		)
	)
	(wire
		(pts
			(xy 226.06 134.62) (xy 248.92 134.62)
		)
		(stroke
			(width 0)
			(type default)
		)
	)
	(wire
		(pts
			(xy 294.64 154.94) (xy 322.58 154.94)
		)
		(stroke
			(width 0)
			(type default)
		)
	)
	(wire
		(pts
			(xy 226.06 160.02) (xy 248.92 160.02)
		)
		(stroke
			(width 0)
			(type default)
		)
	)
	(bus
		(pts
			(xy 68.58 133.35) (xy 68.58 135.89)
		)
		(stroke
			(width 0)
			(type default)
		)
	)
	(wire
		(pts
			(xy 332.74 137.16) (xy 360.68 137.16)
		)
		(stroke
			(width 0)
			(type default)
		)
	)
	(bus
		(pts
			(xy 224.79 135.89) (xy 224.79 138.43)
		)
		(stroke
			(width 0)
			(type default)
		)
	)
	(wire
		(pts
			(xy 104.14 144.78) (xy 132.08 144.78)
		)
		(stroke
			(width 0)
			(type default)
		)
	)
	(bus
		(pts
			(xy 224.79 128.27) (xy 224.79 130.81)
		)
		(stroke
			(width 0)
			(type default)
		)
	)
	(wire
		(pts
			(xy 129.54 116.84) (xy 129.54 119.38)
		)
		(stroke
			(width 0)
			(type default)
		)
	)
	(bus
		(pts
			(xy 201.93 140.97) (xy 201.93 143.51)
		)
		(stroke
			(width 0)
			(type default)
		)
	)
	(wire
		(pts
			(xy 200.66 127) (xy 179.07 127)
		)
		(stroke
			(width 0)
			(type default)
		)
	)
	(wire
		(pts
			(xy 104.14 147.32) (xy 132.08 147.32)
		)
		(stroke
			(width 0)
			(type default)
		)
	)
	(bus
		(pts
			(xy 68.58 135.89) (xy 68.58 138.43)
		)
		(stroke
			(width 0)
			(type default)
		)
	)
	(wire
		(pts
			(xy 200.66 152.4) (xy 179.07 152.4)
		)
		(stroke
			(width 0)
			(type default)
		)
	)
	(bus
		(pts
			(xy 224.79 161.29) (xy 224.79 163.83)
		)
		(stroke
			(width 0)
			(type default)
		)
	)
	(wire
		(pts
			(xy 294.64 119.38) (xy 322.58 119.38)
		)
		(stroke
			(width 0)
			(type default)
		)
	)
	(wire
		(pts
			(xy 226.06 149.86) (xy 248.92 149.86)
		)
		(stroke
			(width 0)
			(type default)
		)
	)
	(wire
		(pts
			(xy 259.08 124.46) (xy 283.21 124.46)
		)
		(stroke
			(width 0)
			(type default)
		)
	)
	(wire
		(pts
			(xy 226.06 142.24) (xy 248.92 142.24)
		)
		(stroke
			(width 0)
			(type default)
		)
	)
	(wire
		(pts
			(xy 69.85 154.94) (xy 93.98 154.94)
		)
		(stroke
			(width 0)
			(type default)
		)
	)
	(wire
		(pts
			(xy 332.74 152.4) (xy 360.68 152.4)
		)
		(stroke
			(width 0)
			(type default)
		)
	)
	(wire
		(pts
			(xy 143.51 144.78) (xy 168.91 144.78)
		)
		(stroke
			(width 0)
			(type default)
		)
	)
	(bus
		(pts
			(xy 64.77 96.52) (xy 64.77 100.33)
		)
		(stroke
			(width 0)
			(type default)
		)
	)
	(bus
		(pts
			(xy 361.95 156.21) (xy 361.95 153.67)
		)
		(stroke
			(width 0)
			(type default)
		)
	)
	(wire
		(pts
			(xy 278.13 114.3) (xy 280.67 114.3)
		)
		(stroke
			(width 0)
			(type default)
		)
	)
	(wire
		(pts
			(xy 143.51 119.38) (xy 168.91 119.38)
		)
		(stroke
			(width 0)
			(type default)
		)
	)
	(wire
		(pts
			(xy 259.08 152.4) (xy 283.21 152.4)
		)
		(stroke
			(width 0)
			(type default)
		)
	)
	(wire
		(pts
			(xy 294.64 144.78) (xy 322.58 144.78)
		)
		(stroke
			(width 0)
			(type default)
		)
	)
	(wire
		(pts
			(xy 69.85 142.24) (xy 93.98 142.24)
		)
		(stroke
			(width 0)
			(type default)
		)
	)
	(wire
		(pts
			(xy 294.64 139.7) (xy 322.58 139.7)
		)
		(stroke
			(width 0)
			(type default)
		)
	)
	(wire
		(pts
			(xy 147.32 162.56) (xy 147.32 160.02)
		)
		(stroke
			(width 0)
			(type default)
		)
	)
	(bus
		(pts
			(xy 68.58 143.51) (xy 68.58 146.05)
		)
		(stroke
			(width 0)
			(type default)
		)
	)
	(wire
		(pts
			(xy 226.06 137.16) (xy 248.92 137.16)
		)
		(stroke
			(width 0)
			(type default)
		)
	)
	(wire
		(pts
			(xy 69.85 157.48) (xy 93.98 157.48)
		)
		(stroke
			(width 0)
			(type default)
		)
	)
	(bus
		(pts
			(xy 361.95 135.89) (xy 361.95 133.35)
		)
		(stroke
			(width 0)
			(type default)
		)
	)
	(bus
		(pts
			(xy 224.79 125.73) (xy 224.79 128.27)
		)
		(stroke
			(width 0)
			(type default)
		)
	)
	(wire
		(pts
			(xy 226.06 162.56) (xy 248.92 162.56)
		)
		(stroke
			(width 0)
			(type default)
		)
	)
	(bus
		(pts
			(xy 361.95 130.81) (xy 361.95 133.35)
		)
		(stroke
			(width 0)
			(type default)
		)
	)
	(wire
		(pts
			(xy 294.64 147.32) (xy 322.58 147.32)
		)
		(stroke
			(width 0)
			(type default)
		)
	)
	(wire
		(pts
			(xy 332.74 119.38) (xy 360.68 119.38)
		)
		(stroke
			(width 0)
			(type default)
		)
	)
	(wire
		(pts
			(xy 278.13 114.3) (xy 278.13 115.57)
		)
		(stroke
			(width 0)
			(type default)
		)
	)
	(wire
		(pts
			(xy 104.14 160.02) (xy 132.08 160.02)
		)
		(stroke
			(width 0)
			(type default)
		)
	)
	(bus
		(pts
			(xy 224.79 120.65) (xy 224.79 123.19)
		)
		(stroke
			(width 0)
			(type default)
		)
	)
	(bus
		(pts
			(xy 29.21 107.95) (xy 33.02 107.95)
		)
		(stroke
			(width 0)
			(type default)
		)
	)
	(bus
		(pts
			(xy 361.95 146.05) (xy 361.95 143.51)
		)
		(stroke
			(width 0)
			(type default)
		)
	)
	(bus
		(pts
			(xy 224.79 123.19) (xy 224.79 125.73)
		)
		(stroke
			(width 0)
			(type default)
		)
	)
	(wire
		(pts
			(xy 147.32 160.02) (xy 147.32 157.48)
		)
		(stroke
			(width 0)
			(type default)
		)
	)
	(wire
		(pts
			(xy 259.08 142.24) (xy 283.21 142.24)
		)
		(stroke
			(width 0)
			(type default)
		)
	)
	(wire
		(pts
			(xy 200.66 132.08) (xy 179.07 132.08)
		)
		(stroke
			(width 0)
			(type default)
		)
	)
	(bus
		(pts
			(xy 224.79 133.35) (xy 224.79 135.89)
		)
		(stroke
			(width 0)
			(type default)
		)
	)
	(bus
		(pts
			(xy 361.95 130.81) (xy 361.95 128.27)
		)
		(stroke
			(width 0)
			(type default)
		)
	)
	(wire
		(pts
			(xy 294.64 152.4) (xy 322.58 152.4)
		)
		(stroke
			(width 0)
			(type default)
		)
	)
	(wire
		(pts
			(xy 143.51 137.16) (xy 168.91 137.16)
		)
		(stroke
			(width 0)
			(type default)
		)
	)
	(wire
		(pts
			(xy 332.74 162.56) (xy 360.68 162.56)
		)
		(stroke
			(width 0)
			(type default)
		)
	)
	(wire
		(pts
			(xy 226.06 139.7) (xy 248.92 139.7)
		)
		(stroke
			(width 0)
			(type default)
		)
	)
	(bus
		(pts
			(xy 224.79 156.21) (xy 224.79 158.75)
		)
		(stroke
			(width 0)
			(type default)
		)
	)
	(wire
		(pts
			(xy 226.06 152.4) (xy 248.92 152.4)
		)
		(stroke
			(width 0)
			(type default)
		)
	)
	(bus
		(pts
			(xy 201.93 118.11) (xy 201.93 120.65)
		)
		(stroke
			(width 0)
			(type default)
		)
	)
	(wire
		(pts
			(xy 69.85 147.32) (xy 93.98 147.32)
		)
		(stroke
			(width 0)
			(type default)
		)
	)
	(wire
		(pts
			(xy 143.51 129.54) (xy 168.91 129.54)
		)
		(stroke
			(width 0)
			(type default)
		)
	)
	(bus
		(pts
			(xy 68.58 148.59) (xy 68.58 153.67)
		)
		(stroke
			(width 0)
			(type default)
		)
	)
	(bus
		(pts
			(xy 201.93 133.35) (xy 201.93 135.89)
		)
		(stroke
			(width 0)
			(type default)
		)
	)
	(bus
		(pts
			(xy 361.95 123.19) (xy 361.95 120.65)
		)
		(stroke
			(width 0)
			(type default)
		)
	)
	(bus
		(pts
			(xy 68.58 138.43) (xy 68.58 140.97)
		)
		(stroke
			(width 0)
			(type default)
		)
	)
	(bus
		(pts
			(xy 361.95 148.59) (xy 361.95 146.05)
		)
		(stroke
			(width 0)
			(type default)
		)
	)
	(wire
		(pts
			(xy 200.66 121.92) (xy 179.07 121.92)
		)
		(stroke
			(width 0)
			(type default)
		)
	)
	(bus
		(pts
			(xy 361.95 125.73) (xy 361.95 128.27)
		)
		(stroke
			(width 0)
			(type default)
		)
	)
	(wire
		(pts
			(xy 332.74 147.32) (xy 360.68 147.32)
		)
		(stroke
			(width 0)
			(type default)
		)
	)
	(wire
		(pts
			(xy 147.32 157.48) (xy 147.32 154.94)
		)
		(stroke
			(width 0)
			(type default)
		)
	)
	(bus
		(pts
			(xy 361.95 151.13) (xy 361.95 148.59)
		)
		(stroke
			(width 0)
			(type default)
		)
	)
	(wire
		(pts
			(xy 69.85 132.08) (xy 93.98 132.08)
		)
		(stroke
			(width 0)
			(type default)
		)
	)
	(bus
		(pts
			(xy 201.93 96.52) (xy 201.93 115.57)
		)
		(stroke
			(width 0)
			(type default)
		)
	)
	(wire
		(pts
			(xy 280.67 114.3) (xy 280.67 116.84)
		)
		(stroke
			(width 0)
			(type default)
		)
	)
	(wire
		(pts
			(xy 129.54 127) (xy 132.08 127)
		)
		(stroke
			(width 0)
			(type default)
		)
	)
	(wire
		(pts
			(xy 259.08 154.94) (xy 283.21 154.94)
		)
		(stroke
			(width 0)
			(type default)
		)
	)
	(bus
		(pts
			(xy 224.79 148.59) (xy 224.79 151.13)
		)
		(stroke
			(width 0)
			(type default)
		)
	)
	(wire
		(pts
			(xy 332.74 116.84) (xy 360.68 116.84)
		)
		(stroke
			(width 0)
			(type default)
		)
	)
	(wire
		(pts
			(xy 69.85 144.78) (xy 93.98 144.78)
		)
		(stroke
			(width 0)
			(type default)
		)
	)
	(wire
		(pts
			(xy 332.74 142.24) (xy 360.68 142.24)
		)
		(stroke
			(width 0)
			(type default)
		)
	)
	(wire
		(pts
			(xy 104.14 165.1) (xy 132.08 165.1)
		)
		(stroke
			(width 0)
			(type default)
		)
	)
	(wire
		(pts
			(xy 259.08 144.78) (xy 283.21 144.78)
		)
		(stroke
			(width 0)
			(type default)
		)
	)
	(bus
		(pts
			(xy 361.95 97.79) (xy 360.68 96.52)
		)
		(stroke
			(width 0)
			(type default)
		)
	)
	(wire
		(pts
			(xy 332.74 144.78) (xy 360.68 144.78)
		)
		(stroke
			(width 0)
			(type default)
		)
	)
	(wire
		(pts
			(xy 332.74 129.54) (xy 360.68 129.54)
		)
		(stroke
			(width 0)
			(type default)
		)
	)
	(wire
		(pts
			(xy 104.14 157.48) (xy 132.08 157.48)
		)
		(stroke
			(width 0)
			(type default)
		)
	)
	(wire
		(pts
			(xy 143.51 116.84) (xy 168.91 116.84)
		)
		(stroke
			(width 0)
			(type default)
		)
	)
	(wire
		(pts
			(xy 35.56 101.6) (xy 43.18 101.6)
		)
		(stroke
			(width 0)
			(type default)
		)
	)
	(wire
		(pts
			(xy 69.85 139.7) (xy 93.98 139.7)
		)
		(stroke
			(width 0)
			(type default)
		)
	)
	(wire
		(pts
			(xy 294.64 127) (xy 322.58 127)
		)
		(stroke
			(width 0)
			(type default)
		)
	)
	(wire
		(pts
			(xy 200.66 149.86) (xy 179.07 149.86)
		)
		(stroke
			(width 0)
			(type default)
		)
	)
	(bus
		(pts
			(xy 224.79 143.51) (xy 224.79 146.05)
		)
		(stroke
			(width 0)
			(type default)
		)
	)
	(bus
		(pts
			(xy 201.93 96.52) (xy 224.79 96.52)
		)
		(stroke
			(width 0)
			(type default)
		)
	)
	(bus
		(pts
			(xy 68.58 156.21) (xy 68.58 158.75)
		)
		(stroke
			(width 0)
			(type default)
		)
	)
	(wire
		(pts
			(xy 259.08 129.54) (xy 283.21 129.54)
		)
		(stroke
			(width 0)
			(type default)
		)
	)
	(wire
		(pts
			(xy 143.51 132.08) (xy 168.91 132.08)
		)
		(stroke
			(width 0)
			(type default)
		)
	)
	(wire
		(pts
			(xy 226.06 147.32) (xy 248.92 147.32)
		)
		(stroke
			(width 0)
			(type default)
		)
	)
	(wire
		(pts
			(xy 259.08 147.32) (xy 283.21 147.32)
		)
		(stroke
			(width 0)
			(type default)
		)
	)
	(wire
		(pts
			(xy 332.74 124.46) (xy 360.68 124.46)
		)
		(stroke
			(width 0)
			(type default)
		)
	)
	(wire
		(pts
			(xy 294.64 165.1) (xy 322.58 165.1)
		)
		(stroke
			(width 0)
			(type default)
		)
	)
	(wire
		(pts
			(xy 200.66 137.16) (xy 179.07 137.16)
		)
		(stroke
			(width 0)
			(type default)
		)
	)
	(wire
		(pts
			(xy 46.99 104.14) (xy 63.5 104.14)
		)
		(stroke
			(width 0)
			(type default)
		)
	)
	(bus
		(pts
			(xy 68.58 140.97) (xy 68.58 143.51)
		)
		(stroke
			(width 0)
			(type default)
		)
	)
	(wire
		(pts
			(xy 104.14 139.7) (xy 132.08 139.7)
		)
		(stroke
			(width 0)
			(type default)
		)
	)
	(wire
		(pts
			(xy 200.66 139.7) (xy 179.07 139.7)
		)
		(stroke
			(width 0)
			(type default)
		)
	)
	(bus
		(pts
			(xy 68.58 130.81) (xy 68.58 133.35)
		)
		(stroke
			(width 0)
			(type default)
		)
	)
	(wire
		(pts
			(xy 129.54 119.38) (xy 129.54 121.92)
		)
		(stroke
			(width 0)
			(type default)
		)
	)
	(wire
		(pts
			(xy 200.66 129.54) (xy 179.07 129.54)
		)
		(stroke
			(width 0)
			(type default)
		)
	)
	(wire
		(pts
			(xy 294.64 149.86) (xy 322.58 149.86)
		)
		(stroke
			(width 0)
			(type default)
		)
	)
	(wire
		(pts
			(xy 104.14 154.94) (xy 132.08 154.94)
		)
		(stroke
			(width 0)
			(type default)
		)
	)
	(wire
		(pts
			(xy 294.64 157.48) (xy 322.58 157.48)
		)
		(stroke
			(width 0)
			(type default)
		)
	)
	(bus
		(pts
			(xy 201.93 125.73) (xy 201.93 128.27)
		)
		(stroke
			(width 0)
			(type default)
		)
	)
	(wire
		(pts
			(xy 294.64 132.08) (xy 322.58 132.08)
		)
		(stroke
			(width 0)
			(type default)
		)
	)
	(bus
		(pts
			(xy 201.93 130.81) (xy 201.93 133.35)
		)
		(stroke
			(width 0)
			(type default)
		)
	)
	(bus
		(pts
			(xy 224.79 151.13) (xy 224.79 153.67)
		)
		(stroke
			(width 0)
			(type default)
		)
	)
	(wire
		(pts
			(xy 149.86 165.1) (xy 147.32 165.1)
		)
		(stroke
			(width 0)
			(type default)
		)
	)
	(wire
		(pts
			(xy 332.74 149.86) (xy 360.68 149.86)
		)
		(stroke
			(width 0)
			(type default)
		)
	)
	(bus
		(pts
			(xy 68.58 153.67) (xy 68.58 156.21)
		)
		(stroke
			(width 0)
			(type default)
		)
	)
	(bus
		(pts
			(xy 201.93 128.27) (xy 201.93 130.81)
		)
		(stroke
			(width 0)
			(type default)
		)
	)
	(wire
		(pts
			(xy 226.06 144.78) (xy 248.92 144.78)
		)
		(stroke
			(width 0)
			(type default)
		)
	)
	(wire
		(pts
			(xy 129.54 116.84) (xy 132.08 116.84)
		)
		(stroke
			(width 0)
			(type default)
		)
	)
	(wire
		(pts
			(xy 280.67 116.84) (xy 280.67 119.38)
		)
		(stroke
			(width 0)
			(type default)
		)
	)
	(wire
		(pts
			(xy 200.66 147.32) (xy 179.07 147.32)
		)
		(stroke
			(width 0)
			(type default)
		)
	)
	(wire
		(pts
			(xy 143.51 142.24) (xy 168.91 142.24)
		)
		(stroke
			(width 0)
			(type default)
		)
	)
	(wire
		(pts
			(xy 294.64 134.62) (xy 322.58 134.62)
		)
		(stroke
			(width 0)
			(type default)
		)
	)
	(bus
		(pts
			(xy 201.93 146.05) (xy 201.93 148.59)
		)
		(stroke
			(width 0)
			(type default)
		)
	)
	(wire
		(pts
			(xy 259.08 137.16) (xy 283.21 137.16)
		)
		(stroke
			(width 0)
			(type default)
		)
	)
	(wire
		(pts
			(xy 125.73 116.84) (xy 129.54 116.84)
		)
		(stroke
			(width 0)
			(type default)
		)
	)
	(wire
		(pts
			(xy 104.14 134.62) (xy 132.08 134.62)
		)
		(stroke
			(width 0)
			(type default)
		)
	)
	(wire
		(pts
			(xy 226.06 124.46) (xy 248.92 124.46)
		)
		(stroke
			(width 0)
			(type default)
		)
	)
	(bus
		(pts
			(xy 201.93 115.57) (xy 201.93 118.11)
		)
		(stroke
			(width 0)
			(type default)
		)
	)
	(wire
		(pts
			(xy 294.64 116.84) (xy 322.58 116.84)
		)
		(stroke
			(width 0)
			(type default)
		)
	)
	(wire
		(pts
			(xy 259.08 134.62) (xy 283.21 134.62)
		)
		(stroke
			(width 0)
			(type default)
		)
	)
	(wire
		(pts
			(xy 143.51 165.1) (xy 147.32 165.1)
		)
		(stroke
			(width 0)
			(type default)
		)
	)
	(wire
		(pts
			(xy 69.85 162.56) (xy 93.98 162.56)
		)
		(stroke
			(width 0)
			(type default)
		)
	)
	(wire
		(pts
			(xy 259.08 157.48) (xy 283.21 157.48)
		)
		(stroke
			(width 0)
			(type default)
		)
	)
	(wire
		(pts
			(xy 332.74 165.1) (xy 360.68 165.1)
		)
		(stroke
			(width 0)
			(type default)
		)
	)
	(wire
		(pts
			(xy 143.51 160.02) (xy 147.32 160.02)
		)
		(stroke
			(width 0)
			(type default)
		)
	)
	(wire
		(pts
			(xy 104.14 132.08) (xy 132.08 132.08)
		)
		(stroke
			(width 0)
			(type default)
		)
	)
	(wire
		(pts
			(xy 332.74 154.94) (xy 360.68 154.94)
		)
		(stroke
			(width 0)
			(type default)
		)
	)
	(wire
		(pts
			(xy 200.66 116.84) (xy 179.07 116.84)
		)
		(stroke
			(width 0)
			(type default)
		)
	)
	(wire
		(pts
			(xy 200.66 119.38) (xy 179.07 119.38)
		)
		(stroke
			(width 0)
			(type default)
		)
	)
	(bus
		(pts
			(xy 361.95 140.97) (xy 361.95 138.43)
		)
		(stroke
			(width 0)
			(type default)
		)
	)
	(bus
		(pts
			(xy 224.79 130.81) (xy 224.79 133.35)
		)
		(stroke
			(width 0)
			(type default)
		)
	)
	(wire
		(pts
			(xy 226.06 132.08) (xy 248.92 132.08)
		)
		(stroke
			(width 0)
			(type default)
		)
	)
	(wire
		(pts
			(xy 226.06 165.1) (xy 248.92 165.1)
		)
		(stroke
			(width 0)
			(type default)
		)
	)
	(wire
		(pts
			(xy 259.08 121.92) (xy 283.21 121.92)
		)
		(stroke
			(width 0)
			(type default)
		)
	)
	(wire
		(pts
			(xy 200.66 134.62) (xy 179.07 134.62)
		)
		(stroke
			(width 0)
			(type default)
		)
	)
	(wire
		(pts
			(xy 104.14 162.56) (xy 132.08 162.56)
		)
		(stroke
			(width 0)
			(type default)
		)
	)
	(wire
		(pts
			(xy 46.99 101.6) (xy 63.5 101.6)
		)
		(stroke
			(width 0)
			(type default)
		)
	)
	(wire
		(pts
			(xy 69.85 137.16) (xy 93.98 137.16)
		)
		(stroke
			(width 0)
			(type default)
		)
	)
	(wire
		(pts
			(xy 294.64 137.16) (xy 322.58 137.16)
		)
		(stroke
			(width 0)
			(type default)
		)
	)
	(bus
		(pts
			(xy 224.79 153.67) (xy 224.79 156.21)
		)
		(stroke
			(width 0)
			(type default)
		)
	)
	(wire
		(pts
			(xy 129.54 124.46) (xy 129.54 127)
		)
		(stroke
			(width 0)
			(type default)
		)
	)
	(bus
		(pts
			(xy 201.93 135.89) (xy 201.93 138.43)
		)
		(stroke
			(width 0)
			(type default)
		)
	)
	(wire
		(pts
			(xy 294.64 160.02) (xy 322.58 160.02)
		)
		(stroke
			(width 0)
			(type default)
		)
	)
	(wire
		(pts
			(xy 226.06 129.54) (xy 248.92 129.54)
		)
		(stroke
			(width 0)
			(type default)
		)
	)
	(wire
		(pts
			(xy 69.85 134.62) (xy 93.98 134.62)
		)
		(stroke
			(width 0)
			(type default)
		)
	)
	(wire
		(pts
			(xy 259.08 165.1) (xy 283.21 165.1)
		)
		(stroke
			(width 0)
			(type default)
		)
	)
	(bus
		(pts
			(xy 201.93 120.65) (xy 201.93 125.73)
		)
		(stroke
			(width 0)
			(type default)
		)
	)
	(wire
		(pts
			(xy 143.51 154.94) (xy 147.32 154.94)
		)
		(stroke
			(width 0)
			(type default)
		)
	)
	(wire
		(pts
			(xy 147.32 165.1) (xy 147.32 162.56)
		)
		(stroke
			(width 0)
			(type default)
		)
	)
	(wire
		(pts
			(xy 332.74 132.08) (xy 360.68 132.08)
		)
		(stroke
			(width 0)
			(type default)
		)
	)
	(wire
		(pts
			(xy 226.06 154.94) (xy 248.92 154.94)
		)
		(stroke
			(width 0)
			(type default)
		)
	)
	(bus
		(pts
			(xy 361.95 143.51) (xy 361.95 140.97)
		)
		(stroke
			(width 0)
			(type default)
		)
	)
	(wire
		(pts
			(xy 294.64 121.92) (xy 322.58 121.92)
		)
		(stroke
			(width 0)
			(type default)
		)
	)
	(wire
		(pts
			(xy 280.67 116.84) (xy 283.21 116.84)
		)
		(stroke
			(width 0)
			(type default)
		)
	)
	(wire
		(pts
			(xy 259.08 162.56) (xy 283.21 162.56)
		)
		(stroke
			(width 0)
			(type default)
		)
	)
	(bus
		(pts
			(xy 64.77 96.52) (xy 68.58 96.52)
		)
		(stroke
			(width 0)
			(type default)
		)
	)
	(wire
		(pts
			(xy 259.08 127) (xy 283.21 127)
		)
		(stroke
			(width 0)
			(type default)
		)
	)
	(bus
		(pts
			(xy 35.56 96.52) (xy 64.77 96.52)
		)
		(stroke
			(width 0)
			(type default)
		)
	)
	(bus
		(pts
			(xy 361.95 163.83) (xy 361.95 161.29)
		)
		(stroke
			(width 0)
			(type default)
		)
	)
	(wire
		(pts
			(xy 143.51 157.48) (xy 147.32 157.48)
		)
		(stroke
			(width 0)
			(type default)
		)
	)
	(wire
		(pts
			(xy 143.51 127) (xy 168.91 127)
		)
		(stroke
			(width 0)
			(type default)
		)
	)
	(bus
		(pts
			(xy 361.95 158.75) (xy 361.95 156.21)
		)
		(stroke
			(width 0)
			(type default)
		)
	)
	(wire
		(pts
			(xy 294.64 142.24) (xy 322.58 142.24)
		)
		(stroke
			(width 0)
			(type default)
		)
	)
	(wire
		(pts
			(xy 143.51 134.62) (xy 168.91 134.62)
		)
		(stroke
			(width 0)
			(type default)
		)
	)
	(wire
		(pts
			(xy 332.74 139.7) (xy 360.68 139.7)
		)
		(stroke
			(width 0)
			(type default)
		)
	)
	(wire
		(pts
			(xy 332.74 157.48) (xy 360.68 157.48)
		)
		(stroke
			(width 0)
			(type default)
		)
	)
	(label "SUP_MCU.INITB"
		(at 229.87 134.62 0)
		(effects
			(font
				(size 1.27 1.27)
			)
			(justify left bottom)
		)
	)
	(label "SUP_MCU.SCLK1"
		(at 335.28 142.24 0)
		(effects
			(font
				(size 1.27 1.27)
			)
			(justify left bottom)
		)
	)
	(label "SUP_MCU.PG_3V3"
		(at 335.28 160.02 0)
		(effects
			(font
				(size 1.27 1.27)
			)
			(justify left bottom)
		)
	)
	(label "SUP_MCU.PG_1V2"
		(at 229.87 147.32 0)
		(effects
			(font
				(size 1.27 1.27)
			)
			(justify left bottom)
		)
	)
	(label "USB_D7"
		(at 265.43 129.54 0)
		(effects
			(font
				(size 1.27 1.27)
			)
			(justify left bottom)
		)
	)
	(label "USB_SPARE1"
		(at 304.8 134.62 0)
		(effects
			(font
				(size 1.27 1.27)
			)
			(justify left bottom)
		)
	)
	(label "RXD1"
		(at 107.95 132.08 0)
		(effects
			(font
				(size 1.27 1.27)
			)
			(justify left bottom)
		)
	)
	(label "SUP_MCU.A0"
		(at 73.66 129.54 0)
		(effects
			(font
				(size 1.27 1.27)
			)
			(justify left bottom)
		)
	)
	(label "PGOOD_1V8"
		(at 153.67 152.4 0)
		(effects
			(font
				(size 1.27 1.27)
			)
			(justify left bottom)
		)
	)
	(label "SUP_MCU.A6"
		(at 181.61 121.92 0)
		(effects
			(font
				(size 1.27 1.27)
			)
			(justify left bottom)
		)
	)
	(label "USB_WR"
		(at 304.8 154.94 0)
		(effects
			(font
				(size 1.27 1.27)
			)
			(justify left bottom)
		)
	)
	(label "USB_D4"
		(at 304.8 119.38 0)
		(effects
			(font
				(size 1.27 1.27)
			)
			(justify left bottom)
		)
	)
	(label "SUP_MCU.A16"
		(at 73.66 142.24 0)
		(effects
			(font
				(size 1.27 1.27)
			)
			(justify left bottom)
		)
	)
	(label "USB_A11"
		(at 153.67 139.7 0)
		(effects
			(font
				(size 1.27 1.27)
			)
			(justify left bottom)
		)
	)
	(label "SUP_MCU.FPGA_M1"
		(at 335.28 137.16 0)
		(effects
			(font
				(size 1.27 1.27)
			)
			(justify left bottom)
		)
	)
	(label "SUP_MCU.A1"
		(at 73.66 137.16 0)
		(effects
			(font
				(size 1.27 1.27)
			)
			(justify left bottom)
		)
	)
	(label "SUP_MCU.~{SCS}"
		(at 229.87 160.02 0)
		(effects
			(font
				(size 1.27 1.27)
			)
			(justify left bottom)
		)
	)
	(label "SUP_MCU.A11"
		(at 181.61 139.7 0)
		(effects
			(font
				(size 1.27 1.27)
			)
			(justify left bottom)
		)
	)
	(label "USB_D2"
		(at 265.43 165.1 0)
		(effects
			(font
				(size 1.27 1.27)
			)
			(justify left bottom)
		)
	)
	(label "USB_A6"
		(at 153.67 121.92 0)
		(effects
			(font
				(size 1.27 1.27)
			)
			(justify left bottom)
		)
	)
	(label "USB_A19"
		(at 153.67 127 0)
		(effects
			(font
				(size 1.27 1.27)
			)
			(justify left bottom)
		)
	)
	(label "SUP_MCU.SPARE0"
		(at 229.87 144.78 0)
		(effects
			(font
				(size 1.27 1.27)
			)
			(justify left bottom)
		)
	)
	(label "USB_CLK1_SPARE"
		(at 304.8 142.24 0)
		(effects
			(font
				(size 1.27 1.27)
			)
			(justify left bottom)
		)
	)
	(label "SDA0"
		(at 107.95 162.56 0)
		(effects
			(font
				(size 1.27 1.27)
			)
			(justify left bottom)
		)
	)
	(label "SUP_MCU.FPGA_MOSI"
		(at 335.28 152.4 0)
		(effects
			(font
				(size 1.27 1.27)
			)
			(justify left bottom)
		)
	)
	(label "TXD1"
		(at 153.67 147.32 0)
		(effects
			(font
				(size 1.27 1.27)
			)
			(justify left bottom)
		)
	)
	(label "USB_A4"
		(at 107.95 165.1 0)
		(effects
			(font
				(size 1.27 1.27)
			)
			(justify left bottom)
		)
	)
	(label "SUP_MCU.A5"
		(at 73.66 157.48 0)
		(effects
			(font
				(size 1.27 1.27)
			)
			(justify left bottom)
		)
	)
	(label "SUP_MCU.A14"
		(at 181.61 129.54 0)
		(effects
			(font
				(size 1.27 1.27)
			)
			(justify left bottom)
		)
	)
	(label "USB_SPARE3"
		(at 304.8 144.78 0)
		(effects
			(font
				(size 1.27 1.27)
			)
			(justify left bottom)
		)
	)
	(label "USB_D6"
		(at 265.43 127 0)
		(effects
			(font
				(size 1.27 1.27)
			)
			(justify left bottom)
		)
	)
	(label "USB_D5"
		(at 304.8 121.92 0)
		(effects
			(font
				(size 1.27 1.27)
			)
			(justify left bottom)
		)
	)
	(label "SUP_MCU.D6"
		(at 229.87 127 0)
		(effects
			(font
				(size 1.27 1.27)
			)
			(justify left bottom)
		)
	)
	(label "SUP_MCU.SCL"
		(at 48.26 104.14 0)
		(effects
			(font
				(size 1.27 1.27)
			)
			(justify left bottom)
		)
	)
	(label "USB_A18"
		(at 107.95 144.78 0)
		(effects
			(font
				(size 1.27 1.27)
			)
			(justify left bottom)
		)
	)
	(label "SUP_MCU.SDA"
		(at 48.26 101.6 0)
		(effects
			(font
				(size 1.27 1.27)
			)
			(justify left bottom)
		)
	)
	(label "SUP_MCU.CE"
		(at 229.87 132.08 0)
		(effects
			(font
				(size 1.27 1.27)
			)
			(justify left bottom)
		)
	)
	(label "SUP_MCU.SPARE3"
		(at 335.28 144.78 0)
		(effects
			(font
				(size 1.27 1.27)
			)
			(justify left bottom)
		)
	)
	(label "PWR_RST"
		(at 107.95 152.4 0)
		(effects
			(font
				(size 1.27 1.27)
			)
			(justify left bottom)
		)
	)
	(label "USB_SPARE2"
		(at 304.8 132.08 0)
		(effects
			(font
				(size 1.27 1.27)
			)
			(justify left bottom)
		)
	)
	(label "USB_SPI_CIPO"
		(at 265.43 157.48 0)
		(effects
			(font
				(size 1.27 1.27)
			)
			(justify left bottom)
		)
	)
	(label "USB_RD"
		(at 304.8 165.1 0)
		(effects
			(font
				(size 1.27 1.27)
			)
			(justify left bottom)
		)
	)
	(label "USB_SPARE0"
		(at 265.43 144.78 0)
		(effects
			(font
				(size 1.27 1.27)
			)
			(justify left bottom)
		)
	)
	(label "USB_A2"
		(at 107.95 154.94 0)
		(effects
			(font
				(size 1.27 1.27)
			)
			(justify left bottom)
		)
	)
	(label "SUP_MCU.PROGRAMB"
		(at 229.87 139.7 0)
		(effects
			(font
				(size 1.27 1.27)
			)
			(justify left bottom)
		)
	)
	(label "USB_D3"
		(at 265.43 124.46 0)
		(effects
			(font
				(size 1.27 1.27)
			)
			(justify left bottom)
		)
	)
	(label "I2C.SCL"
		(at 35.56 104.14 0)
		(effects
			(font
				(size 1.27 1.27)
			)
			(justify left bottom)
		)
	)
	(label "SUP_MCU.D7"
		(at 229.87 129.54 0)
		(effects
			(font
				(size 1.27 1.27)
			)
			(justify left bottom)
		)
	)
	(label "PGOOD_1V2"
		(at 265.43 147.32 0)
		(effects
			(font
				(size 1.27 1.27)
			)
			(justify left bottom)
		)
	)
	(label "SUP_MCU.RX0"
		(at 181.61 149.86 0)
		(effects
			(font
				(size 1.27 1.27)
			)
			(justify left bottom)
		)
	)
	(label "USB_A12"
		(at 153.67 137.16 0)
		(effects
			(font
				(size 1.27 1.27)
			)
			(justify left bottom)
		)
	)
	(label "SUP_MCU.CCLK"
		(at 73.66 149.86 0)
		(effects
			(font
				(size 1.27 1.27)
			)
			(justify left bottom)
		)
	)
	(label "FPGA_M2"
		(at 265.43 149.86 0)
		(effects
			(font
				(size 1.27 1.27)
			)
			(justify left bottom)
		)
	)
	(label "USB_SPI_COPI"
		(at 265.43 154.94 0)
		(effects
			(font
				(size 1.27 1.27)
			)
			(justify left bottom)
		)
	)
	(label "SUP_MCU.SDA"
		(at 73.66 162.56 0)
		(effects
			(font
				(size 1.27 1.27)
			)
			(justify left bottom)
		)
	)
	(label "SUP_MCU.A4"
		(at 73.66 165.1 0)
		(effects
			(font
				(size 1.27 1.27)
			)
			(justify left bottom)
		)
	)
	(label "PGOOD_3V3"
		(at 304.8 160.02 0)
		(effects
			(font
				(size 1.27 1.27)
			)
			(justify left bottom)
		)
	)
	(label "CFG_PROGRAMB"
		(at 265.43 139.7 0)
		(effects
			(font
				(size 1.27 1.27)
			)
			(justify left bottom)
		)
	)
	(label "SUP_MCU.FPGA_M0"
		(at 335.28 129.54 0)
		(effects
			(font
				(size 1.27 1.27)
			)
			(justify left bottom)
		)
	)
	(label "SUP_MCU.FPGA_MISO"
		(at 229.87 142.24 0)
		(effects
			(font
				(size 1.27 1.27)
			)
			(justify left bottom)
		)
	)
	(label "USB_A15"
		(at 153.67 116.84 0)
		(effects
			(font
				(size 1.27 1.27)
			)
			(justify left bottom)
		)
	)
	(label "SUP_MCU.A7"
		(at 73.66 139.7 0)
		(effects
			(font
				(size 1.27 1.27)
			)
			(justify left bottom)
		)
	)
	(label "SUP_MCU.D2"
		(at 229.87 165.1 0)
		(effects
			(font
				(size 1.27 1.27)
			)
			(justify left bottom)
		)
	)
	(label "SUP_MCU.PD_RST"
		(at 335.28 149.86 0)
		(effects
			(font
				(size 1.27 1.27)
			)
			(justify left bottom)
		)
	)
	(label "SUP_MCU.A3"
		(at 73.66 160.02 0)
		(effects
			(font
				(size 1.27 1.27)
			)
			(justify left bottom)
		)
	)
	(label "SUP_MCU.SCL"
		(at 335.28 124.46 0)
		(effects
			(font
				(size 1.27 1.27)
			)
			(justify left bottom)
		)
	)
	(label "SUP_MCU.CLKO"
		(at 181.61 132.08 0)
		(effects
			(font
				(size 1.27 1.27)
			)
			(justify left bottom)
		)
	)
	(label "USB_A16"
		(at 107.95 142.24 0)
		(effects
			(font
				(size 1.27 1.27)
			)
			(justify left bottom)
		)
	)
	(label "FAN_PWM"
		(at 153.67 134.62 0)
		(effects
			(font
				(size 1.27 1.27)
			)
			(justify left bottom)
		)
	)
	(label "SUP_MCU.A2"
		(at 73.66 154.94 0)
		(effects
			(font
				(size 1.27 1.27)
			)
			(justify left bottom)
		)
	)
	(label "SUP_MCU.A13"
		(at 73.66 134.62 0)
		(effects
			(font
				(size 1.27 1.27)
			)
			(justify left bottom)
		)
	)
	(label "SUP_MCU.D4"
		(at 335.28 119.38 0)
		(effects
			(font
				(size 1.27 1.27)
			)
			(justify left bottom)
		)
	)
	(label "USB_ALE"
		(at 304.8 157.48 0)
		(effects
			(font
				(size 1.27 1.27)
			)
			(justify left bottom)
		)
	)
	(label "SUP_MCU.MISO"
		(at 229.87 157.48 0)
		(effects
			(font
				(size 1.27 1.27)
			)
			(justify left bottom)
		)
	)
	(label "SUP_MCU.A17"
		(at 181.61 119.38 0)
		(effects
			(font
				(size 1.27 1.27)
			)
			(justify left bottom)
		)
	)
	(label "SUP_MCU.D1"
		(at 335.28 116.84 0)
		(effects
			(font
				(size 1.27 1.27)
			)
			(justify left bottom)
		)
	)
	(label "FPGA_CFG_CS"
		(at 304.8 139.7 0)
		(effects
			(font
				(size 1.27 1.27)
			)
			(justify left bottom)
		)
	)
	(label "I2C.SDA"
		(at 35.56 101.6 0)
		(effects
			(font
				(size 1.27 1.27)
			)
			(justify left bottom)
		)
	)
	(label "RXD0"
		(at 153.67 149.86 0)
		(effects
			(font
				(size 1.27 1.27)
			)
			(justify left bottom)
		)
	)
	(label "SCL0"
		(at 304.8 124.46 0)
		(effects
			(font
				(size 1.27 1.27)
			)
			(justify left bottom)
		)
	)
	(label "SUP_MCU.A15"
		(at 181.61 116.84 0)
		(effects
			(font
				(size 1.27 1.27)
			)
			(justify left bottom)
		)
	)
	(label "FPGA_M0"
		(at 304.8 129.54 0)
		(effects
			(font
				(size 1.27 1.27)
			)
			(justify left bottom)
		)
	)
	(label "SUP_MCU.A18"
		(at 73.66 144.78 0)
		(effects
			(font
				(size 1.27 1.27)
			)
			(justify left bottom)
		)
	)
	(label "SUP_MCU.WR"
		(at 335.28 154.94 0)
		(effects
			(font
				(size 1.27 1.27)
			)
			(justify left bottom)
		)
	)
	(label "FPGA_COPI"
		(at 304.8 152.4 0)
		(effects
			(font
				(size 1.27 1.27)
			)
			(justify left bottom)
		)
	)
	(label "CFG_DONE"
		(at 265.43 137.16 0)
		(effects
			(font
				(size 1.27 1.27)
			)
			(justify left bottom)
		)
	)
	(label "SUP_MCU.SCLK0"
		(at 229.87 162.56 0)
		(effects
			(font
				(size 1.27 1.27)
			)
			(justify left bottom)
		)
	)
	(label "FPGA_M1"
		(at 304.8 137.16 0)
		(effects
			(font
				(size 1.27 1.27)
			)
			(justify left bottom)
		)
	)
	(label "USB_CLK0"
		(at 153.67 132.08 0)
		(effects
			(font
				(size 1.27 1.27)
			)
			(justify left bottom)
		)
	)
	(label "PGOOD_VCCINT"
		(at 304.8 147.32 0)
		(effects
			(font
				(size 1.27 1.27)
			)
			(justify left bottom)
		)
	)
	(label "USB_A17"
		(at 153.67 119.38 0)
		(effects
			(font
				(size 1.27 1.27)
			)
			(justify left bottom)
		)
	)
	(label "TEMP_ALERT_N"
		(at 304.8 127 0)
		(effects
			(font
				(size 1.27 1.27)
			)
			(justify left bottom)
		)
	)
	(label "USB_A3"
		(at 107.95 160.02 0)
		(effects
			(font
				(size 1.27 1.27)
			)
			(justify left bottom)
		)
	)
	(label "SUP_MCU.TX1"
		(at 181.61 147.32 0)
		(effects
			(font
				(size 1.27 1.27)
			)
			(justify left bottom)
		)
	)
	(label "USB_D1"
		(at 304.8 116.84 0)
		(effects
			(font
				(size 1.27 1.27)
			)
			(justify left bottom)
		)
	)
	(label "SUP_MCU.D0"
		(at 229.87 121.92 0)
		(effects
			(font
				(size 1.27 1.27)
			)
			(justify left bottom)
		)
	)
	(label "USB_A14"
		(at 153.67 129.54 0)
		(effects
			(font
				(size 1.27 1.27)
			)
			(justify left bottom)
		)
	)
	(label "USB_D0"
		(at 265.43 121.92 0)
		(effects
			(font
				(size 1.27 1.27)
			)
			(justify left bottom)
		)
	)
	(label "USB_A13"
		(at 107.95 134.62 0)
		(effects
			(font
				(size 1.27 1.27)
			)
			(justify left bottom)
		)
	)
	(label "SW_STATE"
		(at 107.95 147.32 0)
		(effects
			(font
				(size 1.27 1.27)
			)
			(justify left bottom)
		)
	)
	(label "SUP_MCU.A12"
		(at 181.61 137.16 0)
		(effects
			(font
				(size 1.27 1.27)
			)
			(justify left bottom)
		)
	)
	(label "SUP_MCU.A8"
		(at 229.87 152.4 0)
		(effects
			(font
				(size 1.27 1.27)
			)
			(justify left bottom)
		)
	)
	(label "USB_A5"
		(at 107.95 157.48 0)
		(effects
			(font
				(size 1.27 1.27)
			)
			(justify left bottom)
		)
	)
	(label "SUP_MCU.FAN_PWM"
		(at 181.61 134.62 0)
		(effects
			(font
				(size 1.27 1.27)
			)
			(justify left bottom)
		)
	)
	(label "SUP_MCU.D5"
		(at 335.28 121.92 0)
		(effects
			(font
				(size 1.27 1.27)
			)
			(justify left bottom)
		)
	)
	(label "USB_C_PD_RST"
		(at 304.8 149.86 0)
		(effects
			(font
				(size 1.27 1.27)
			)
			(justify left bottom)
		)
	)
	(label "TXD0"
		(at 153.67 144.78 0)
		(effects
			(font
				(size 1.27 1.27)
			)
			(justify left bottom)
		)
	)
	(label "SUP_MCU.TX0"
		(at 181.61 144.78 0)
		(effects
			(font
				(size 1.27 1.27)
			)
			(justify left bottom)
		)
	)
	(label "USB_SPI_SCK"
		(at 265.43 162.56 0)
		(effects
			(font
				(size 1.27 1.27)
			)
			(justify left bottom)
		)
	)
	(label "USB_A8"
		(at 265.43 152.4 0)
		(effects
			(font
				(size 1.27 1.27)
			)
			(justify left bottom)
		)
	)
	(label "SUP_MCU.RD"
		(at 335.28 165.1 0)
		(effects
			(font
				(size 1.27 1.27)
			)
			(justify left bottom)
		)
	)
	(label "SUP_MCU.PG_1V8"
		(at 181.61 152.4 0)
		(effects
			(font
				(size 1.27 1.27)
			)
			(justify left bottom)
		)
	)
	(label "USB_A0"
		(at 107.95 129.54 0)
		(effects
			(font
				(size 1.27 1.27)
			)
			(justify left bottom)
		)
	)
	(label "SUP_MCU.TEMP_ALERT_N"
		(at 335.28 127 0)
		(effects
			(font
				(size 1.27 1.27)
			)
			(justify left bottom)
		)
	)
	(label "USB_A1"
		(at 107.95 137.16 0)
		(effects
			(font
				(size 1.27 1.27)
			)
			(justify left bottom)
		)
	)
	(label "SUP_MCU.CFG_CS"
		(at 335.28 139.7 0)
		(effects
			(font
				(size 1.27 1.27)
			)
			(justify left bottom)
		)
	)
	(label "SUP_MCU.ALE"
		(at 335.28 157.48 0)
		(effects
			(font
				(size 1.27 1.27)
			)
			(justify left bottom)
		)
	)
	(label "SAM_FPGA_CCLK"
		(at 107.95 149.86 0)
		(effects
			(font
				(size 1.27 1.27)
			)
			(justify left bottom)
		)
	)
	(label "FPGA_CIPO"
		(at 265.43 142.24 0)
		(effects
			(font
				(size 1.27 1.27)
			)
			(justify left bottom)
		)
	)
	(label "SUP_MCU.RX1"
		(at 73.66 132.08 0)
		(effects
			(font
				(size 1.27 1.27)
			)
			(justify left bottom)
		)
	)
	(label "SUP_MCU.SW_STATE"
		(at 73.66 147.32 0)
		(effects
			(font
				(size 1.27 1.27)
			)
			(justify left bottom)
		)
	)
	(label "SUP_MCU.FPGA_M2"
		(at 229.87 149.86 0)
		(effects
			(font
				(size 1.27 1.27)
			)
			(justify left bottom)
		)
	)
	(label "SUP_MCU.A19"
		(at 181.61 127 0)
		(effects
			(font
				(size 1.27 1.27)
			)
			(justify left bottom)
		)
	)
	(label "USB_CE"
		(at 265.43 132.08 0)
		(effects
			(font
				(size 1.27 1.27)
			)
			(justify left bottom)
		)
	)
	(label "SUP_MCU.A9"
		(at 335.28 162.56 0)
		(effects
			(font
				(size 1.27 1.27)
			)
			(justify left bottom)
		)
	)
	(label "SUP_MCU.D3"
		(at 229.87 124.46 0)
		(effects
			(font
				(size 1.27 1.27)
			)
			(justify left bottom)
		)
	)
	(label "USB_A9"
		(at 304.8 162.56 0)
		(effects
			(font
				(size 1.27 1.27)
			)
			(justify left bottom)
		)
	)
	(label "SUP_MCU.SPARE2"
		(at 335.28 132.08 0)
		(effects
			(font
				(size 1.27 1.27)
			)
			(justify left bottom)
		)
	)
	(label "SUP_MCU.PG_VCCINT"
		(at 335.28 147.32 0)
		(effects
			(font
				(size 1.27 1.27)
			)
			(justify left bottom)
		)
	)
	(label "SUP_MCU.MOSI"
		(at 229.87 154.94 0)
		(effects
			(font
				(size 1.27 1.27)
			)
			(justify left bottom)
		)
	)
	(label "USB_A10"
		(at 153.67 142.24 0)
		(effects
			(font
				(size 1.27 1.27)
			)
			(justify left bottom)
		)
	)
	(label "CFG_INITB"
		(at 265.43 134.62 0)
		(effects
			(font
				(size 1.27 1.27)
			)
			(justify left bottom)
		)
	)
	(label "SUP_MCU.DONE"
		(at 229.87 137.16 0)
		(effects
			(font
				(size 1.27 1.27)
			)
			(justify left bottom)
		)
	)
	(label "USB_A7"
		(at 107.95 139.7 0)
		(effects
			(font
				(size 1.27 1.27)
			)
			(justify left bottom)
		)
	)
	(label "PWR_ON"
		(at 153.67 124.46 0)
		(effects
			(font
				(size 1.27 1.27)
			)
			(justify left bottom)
		)
	)
	(label "USB_SPI_CS"
		(at 265.43 160.02 0)
		(effects
			(font
				(size 1.27 1.27)
			)
			(justify left bottom)
		)
	)
	(label "SUP_MCU.A10"
		(at 181.61 142.24 0)
		(effects
			(font
				(size 1.27 1.27)
			)
			(justify left bottom)
		)
	)
	(label "SUP_MCU.SPARE1"
		(at 335.28 134.62 0)
		(effects
			(font
				(size 1.27 1.27)
			)
			(justify left bottom)
		)
	)
	(hierarchical_label "I2C{I2C}"
		(shape bidirectional)
		(at 29.21 107.95 180)
		(effects
			(font
				(size 1.27 1.27)
			)
			(justify right)
		)
	)
	(hierarchical_label "SUP_MCU{SUP-MCU}"
		(shape bidirectional)
		(at 35.56 96.52 180)
		(effects
			(font
				(size 1.27 1.27)
			)
			(justify right)
		)
	)
	(symbol
		(lib_id "antmicroResistorNetworksArrays:R_4x33R_0201_array")
		(at 248.92 137.16 0)
		(unit 1)
		(exclude_from_sim no)
		(in_bom yes)
		(on_board yes)
		(dnp no)
		(property "Reference" "R30"
			(at 254 106.68 0)
			(effects
				(font
					(size 1.27 1.27)
				)
			)
		)
		(property "Value" "R_4x33R_0201_array"
			(at 275.59 142.875 0)
			(effects
				(font
					(size 1.27 1.27)
					(thickness 0.15)
				)
				(justify left bottom)
				(hide yes)
			)
		)
		(property "Footprint" "antmicro-footprints:R_Array_4x0201_Panasonic_EXB18V"
			(at 275.59 147.955 0)
			(effects
				(font
					(size 1.27 1.27)
					(thickness 0.15)
				)
				(justify left bottom)
				(hide yes)
			)
		)
		(property "Datasheet" "http://industrial.panasonic.com/cdbs/www-data/pdf/AOC0000/AOC0000C14.pdf"
			(at 275.59 150.495 0)
			(effects
				(font
					(size 1.27 1.27)
					(thickness 0.15)
				)
				(justify left bottom)
				(hide yes)
			)
		)
		(property "Description" ""
			(at 248.92 137.16 0)
			(effects
				(font
					(size 1.27 1.27)
				)
			)
		)
		(property "MPN" "EXB-18V330JX"
			(at 275.59 153.035 0)
			(effects
				(font
					(size 1.27 1.27)
					(thickness 0.15)
				)
				(justify left bottom)
				(hide yes)
			)
		)
		(property "Manufacturer" "Panasonic"
			(at 275.59 155.575 0)
			(effects
				(font
					(size 1.27 1.27)
					(thickness 0.15)
				)
				(justify left bottom)
				(hide yes)
			)
		)
		(property "Author" "Antmicro"
			(at 275.59 158.115 0)
			(effects
				(font
					(size 1.27 1.27)
					(thickness 0.15)
				)
				(justify left bottom)
				(hide yes)
			)
		)
		(property "License" "Apache-2.0"
			(at 275.59 160.655 0)
			(effects
				(font
					(size 1.27 1.27)
					(thickness 0.15)
				)
				(justify left bottom)
				(hide yes)
			)
		)
		(property "Val" "R_4x33R_0201"
			(at 262.255 140.335 0)
			(effects
				(font
					(size 1.27 1.27)
				)
				(justify left bottom)
				(hide yes)
			)
		)
		(pin "1"
		)
		(pin "2"
		)
		(pin "3"
		)
		(pin "4"
		)
		(pin "5"
		)
		(pin "6"
		)
		(pin "7"
		)
		(pin "8"
		)
		(instances
			(project "k410t-devboard"
				(path ""
					(reference "R30")
					(unit 1)
				)
			)
		)
	)
	(symbol
		(lib_id "antmicroResistorNetworksArrays:R_4x33R_0201_array")
		(at 322.58 127 0)
		(unit 1)
		(exclude_from_sim no)
		(in_bom yes)
		(on_board yes)
		(dnp no)
		(property "Reference" "R42"
			(at 327.66 104.9566 0)
			(effects
				(font
					(size 1.27 1.27)
				)
			)
		)
		(property "Value" "R_4x33R_0201_array"
			(at 349.25 132.715 0)
			(effects
				(font
					(size 1.27 1.27)
					(thickness 0.15)
				)
				(justify left bottom)
				(hide yes)
			)
		)
		(property "Footprint" "antmicro-footprints:R_Array_4x0201_Panasonic_EXB18V"
			(at 349.25 137.795 0)
			(effects
				(font
					(size 1.27 1.27)
					(thickness 0.15)
				)
				(justify left bottom)
				(hide yes)
			)
		)
		(property "Datasheet" "http://industrial.panasonic.com/cdbs/www-data/pdf/AOC0000/AOC0000C14.pdf"
			(at 349.25 140.335 0)
			(effects
				(font
					(size 1.27 1.27)
					(thickness 0.15)
				)
				(justify left bottom)
				(hide yes)
			)
		)
		(property "Description" ""
			(at 322.58 127 0)
			(effects
				(font
					(size 1.27 1.27)
				)
			)
		)
		(property "MPN" "EXB-18V330JX"
			(at 349.25 142.875 0)
			(effects
				(font
					(size 1.27 1.27)
					(thickness 0.15)
				)
				(justify left bottom)
				(hide yes)
			)
		)
		(property "Manufacturer" "Panasonic"
			(at 349.25 145.415 0)
			(effects
				(font
					(size 1.27 1.27)
					(thickness 0.15)
				)
				(justify left bottom)
				(hide yes)
			)
		)
		(property "Author" "Antmicro"
			(at 349.25 147.955 0)
			(effects
				(font
					(size 1.27 1.27)
					(thickness 0.15)
				)
				(justify left bottom)
				(hide yes)
			)
		)
		(property "License" "Apache-2.0"
			(at 349.25 150.495 0)
			(effects
				(font
					(size 1.27 1.27)
					(thickness 0.15)
				)
				(justify left bottom)
				(hide yes)
			)
		)
		(property "Val" "R_4x33R_0201"
			(at 349.25 135.255 0)
			(effects
				(font
					(size 1.27 1.27)
				)
				(justify left bottom)
				(hide yes)
			)
		)
		(pin "1"
		)
		(pin "2"
		)
		(pin "3"
		)
		(pin "4"
		)
		(pin "5"
		)
		(pin "6"
		)
		(pin "7"
		)
		(pin "8"
		)
		(instances
			(project "k410t-devboard"
				(path ""
					(reference "R42")
					(unit 1)
				)
			)
		)
	)
	(symbol
		(lib_id "antmicroResistorNetworksArrays:R_4x33R_0201_array")
		(at 93.98 157.48 0)
		(unit 1)
		(exclude_from_sim no)
		(in_bom yes)
		(on_board yes)
		(dnp no)
		(property "Reference" "R23"
			(at 99.06 120.65 0)
			(effects
				(font
					(size 1.27 1.27)
				)
			)
		)
		(property "Value" "R_4x33R_0201_array"
			(at 120.65 163.195 0)
			(effects
				(font
					(size 1.27 1.27)
					(thickness 0.15)
				)
				(justify left bottom)
				(hide yes)
			)
		)
		(property "Footprint" "antmicro-footprints:R_Array_4x0201_Panasonic_EXB18V"
			(at 120.65 168.275 0)
			(effects
				(font
					(size 1.27 1.27)
					(thickness 0.15)
				)
				(justify left bottom)
				(hide yes)
			)
		)
		(property "Datasheet" "http://industrial.panasonic.com/cdbs/www-data/pdf/AOC0000/AOC0000C14.pdf"
			(at 120.65 170.815 0)
			(effects
				(font
					(size 1.27 1.27)
					(thickness 0.15)
				)
				(justify left bottom)
				(hide yes)
			)
		)
		(property "Description" ""
			(at 93.98 157.48 0)
			(effects
				(font
					(size 1.27 1.27)
				)
			)
		)
		(property "MPN" "EXB-18V330JX"
			(at 120.65 173.355 0)
			(effects
				(font
					(size 1.27 1.27)
					(thickness 0.15)
				)
				(justify left bottom)
				(hide yes)
			)
		)
		(property "Manufacturer" "Panasonic"
			(at 120.65 175.895 0)
			(effects
				(font
					(size 1.27 1.27)
					(thickness 0.15)
				)
				(justify left bottom)
				(hide yes)
			)
		)
		(property "Author" "Antmicro"
			(at 120.65 178.435 0)
			(effects
				(font
					(size 1.27 1.27)
					(thickness 0.15)
				)
				(justify left bottom)
				(hide yes)
			)
		)
		(property "License" "Apache-2.0"
			(at 120.65 180.975 0)
			(effects
				(font
					(size 1.27 1.27)
					(thickness 0.15)
				)
				(justify left bottom)
				(hide yes)
			)
		)
		(property "Val" "R_4x33R_0201"
			(at 120.65 165.735 0)
			(effects
				(font
					(size 1.27 1.27)
				)
				(justify left bottom)
				(hide yes)
			)
		)
		(pin "1"
		)
		(pin "2"
		)
		(pin "3"
		)
		(pin "4"
		)
		(pin "5"
		)
		(pin "6"
		)
		(pin "7"
		)
		(pin "8"
		)
		(instances
			(project "k410t-devboard"
				(path ""
					(reference "R23")
					(unit 1)
				)
			)
		)
	)
	(symbol
		(lib_id "antmicroResistorNetworksArrays:R_4x33R_0201_array")
		(at 168.91 114.3 0)
		(unit 1)
		(exclude_from_sim no)
		(in_bom yes)
		(on_board yes)
		(dnp no)
		(property "Reference" "R24"
			(at 173.99 102.235 0)
			(effects
				(font
					(size 1.27 1.27)
				)
			)
		)
		(property "Value" "R_4x33R_0201_array"
			(at 195.58 120.015 0)
			(effects
				(font
					(size 1.27 1.27)
					(thickness 0.15)
				)
				(justify left bottom)
				(hide yes)
			)
		)
		(property "Footprint" "antmicro-footprints:R_Array_4x0201_Panasonic_EXB18V"
			(at 195.58 125.095 0)
			(effects
				(font
					(size 1.27 1.27)
					(thickness 0.15)
				)
				(justify left bottom)
				(hide yes)
			)
		)
		(property "Datasheet" "http://industrial.panasonic.com/cdbs/www-data/pdf/AOC0000/AOC0000C14.pdf"
			(at 195.58 127.635 0)
			(effects
				(font
					(size 1.27 1.27)
					(thickness 0.15)
				)
				(justify left bottom)
				(hide yes)
			)
		)
		(property "Description" ""
			(at 168.91 114.3 0)
			(effects
				(font
					(size 1.27 1.27)
				)
			)
		)
		(property "MPN" "EXB-18V330JX"
			(at 195.58 130.175 0)
			(effects
				(font
					(size 1.27 1.27)
					(thickness 0.15)
				)
				(justify left bottom)
				(hide yes)
			)
		)
		(property "Manufacturer" "Panasonic"
			(at 195.58 132.715 0)
			(effects
				(font
					(size 1.27 1.27)
					(thickness 0.15)
				)
				(justify left bottom)
				(hide yes)
			)
		)
		(property "Author" "Antmicro"
			(at 195.58 135.255 0)
			(effects
				(font
					(size 1.27 1.27)
					(thickness 0.15)
				)
				(justify left bottom)
				(hide yes)
			)
		)
		(property "License" "Apache-2.0"
			(at 195.58 137.795 0)
			(effects
				(font
					(size 1.27 1.27)
					(thickness 0.15)
				)
				(justify left bottom)
				(hide yes)
			)
		)
		(property "Val" "R_4x33R_0201"
			(at 173.99 111.125 0)
			(effects
				(font
					(size 1.27 1.27)
				)
			)
		)
		(pin "1"
		)
		(pin "2"
		)
		(pin "3"
		)
		(pin "4"
		)
		(pin "5"
		)
		(pin "6"
		)
		(pin "7"
		)
		(pin "8"
		)
		(instances
			(project "k410t-devboard"
				(path ""
					(reference "R24")
					(unit 1)
				)
			)
		)
	)
	(symbol
		(lib_id "antmicroB2BConnectors:Socket_Samtec_ERF5_2x20_ERF5-020-05.0-L-DV-K-TR")
		(at 132.08 116.84 0)
		(unit 1)
		(exclude_from_sim no)
		(in_bom yes)
		(on_board yes)
		(dnp no)
		(fields_autoplaced yes)
		(property "Reference" "J21"
			(at 137.795 109.22 0)
			(effects
				(font
					(size 1.27 1.27)
					(thickness 0.15)
				)
			)
		)
		(property "Value" "Socket_Samtec_ERF5_2x20_ERF5-020-05.0-L-DV-K-TR"
			(at 158.75 121.92 0)
			(effects
				(font
					(size 1.27 1.27)
					(thickness 0.15)
				)
				(justify left bottom)
				(hide yes)
			)
		)
		(property "Footprint" "antmicro-footprints:Conn_Socket_Samtec_ERF5_2x20_ERF5-020-05.0-L-DV-K-TR"
			(at 158.75 124.46 0)
			(effects
				(font
					(size 1.27 1.27)
					(thickness 0.15)
				)
				(justify left bottom)
				(hide yes)
			)
		)
		(property "Datasheet" "https://suddendocs.samtec.com/productspecs/erm5-erf5.pdf?_gl=1*1g914su*_ga*MTE0MzExNjY4MC4xNjcyMTQ5NTUz*_ga_3KFNZC07WW*MTY3Mjg0NzY5Ny42LjEuMTY3Mjg0ODE3MS42MC4wLjA."
			(at 158.75 127 0)
			(effects
				(font
					(size 1.27 1.27)
					(thickness 0.15)
				)
				(justify left bottom)
				(hide yes)
			)
		)
		(property "Description" ""
			(at 132.08 116.84 0)
			(effects
				(font
					(size 1.27 1.27)
				)
			)
		)
		(property "MPN" "ERF5-020-05.0-L-DV-K-TR"
			(at 137.795 111.76 0)
			(effects
				(font
					(size 1.27 1.27)
					(thickness 0.15)
				)
			)
		)
		(property "Manufacturer" "Samtec"
			(at 158.75 129.54 0)
			(effects
				(font
					(size 1.27 1.27)
					(thickness 0.15)
				)
				(justify left bottom)
				(hide yes)
			)
		)
		(property "Author" "Antmicro"
			(at 158.75 134.62 0)
			(effects
				(font
					(size 1.27 1.27)
					(thickness 0.15)
				)
				(justify left bottom)
				(hide yes)
			)
		)
		(property "License" "Apache-2.0"
			(at 158.75 137.16 0)
			(effects
				(font
					(size 1.27 1.27)
					(thickness 0.15)
				)
				(justify left bottom)
				(hide yes)
			)
		)
		(property "Pitch" "0.5 mm"
			(at 158.75 132.08 0)
			(effects
				(font
					(size 1.27 1.27)
				)
				(justify left bottom)
				(hide yes)
			)
		)
		(pin "29"
		)
		(pin "19"
		)
		(pin "14"
		)
		(pin "13"
		)
		(pin "11"
		)
		(pin "15"
		)
		(pin "12"
		)
		(pin "16"
		)
		(pin "1"
		)
		(pin "3"
		)
		(pin "7"
		)
		(pin "28"
		)
		(pin "37"
		)
		(pin "26"
		)
		(pin "10"
		)
		(pin "39"
		)
		(pin "35"
		)
		(pin "31"
		)
		(pin "9"
		)
		(pin "21"
		)
		(pin "4"
		)
		(pin "17"
		)
		(pin "40"
		)
		(pin "36"
		)
		(pin "20"
		)
		(pin "5"
		)
		(pin "22"
		)
		(pin "38"
		)
		(pin "33"
		)
		(pin "8"
		)
		(pin "34"
		)
		(pin "27"
		)
		(pin "18"
		)
		(pin "6"
		)
		(pin "2"
		)
		(pin "23"
		)
		(pin "25"
		)
		(pin "30"
		)
		(pin "24"
		)
		(pin "32"
		)
		(instances
			(project "k410t-devboard"
				(path ""
					(reference "J21")
					(unit 1)
				)
			)
		)
	)
	(symbol
		(lib_id "antmicroResistorNetworksArrays:R_4x33R_0201_array")
		(at 93.98 137.16 0)
		(unit 1)
		(exclude_from_sim no)
		(in_bom yes)
		(on_board yes)
		(dnp no)
		(property "Reference" "R21"
			(at 99.06 116.84 0)
			(effects
				(font
					(size 1.27 1.27)
				)
			)
		)
		(property "Value" "R_4x33R_0201_array"
			(at 120.65 142.875 0)
			(effects
				(font
					(size 1.27 1.27)
					(thickness 0.15)
				)
				(justify left bottom)
				(hide yes)
			)
		)
		(property "Footprint" "antmicro-footprints:R_Array_4x0201_Panasonic_EXB18V"
			(at 120.65 147.955 0)
			(effects
				(font
					(size 1.27 1.27)
					(thickness 0.15)
				)
				(justify left bottom)
				(hide yes)
			)
		)
		(property "Datasheet" "http://industrial.panasonic.com/cdbs/www-data/pdf/AOC0000/AOC0000C14.pdf"
			(at 120.65 150.495 0)
			(effects
				(font
					(size 1.27 1.27)
					(thickness 0.15)
				)
				(justify left bottom)
				(hide yes)
			)
		)
		(property "Description" ""
			(at 93.98 137.16 0)
			(effects
				(font
					(size 1.27 1.27)
				)
			)
		)
		(property "MPN" "EXB-18V330JX"
			(at 120.65 153.035 0)
			(effects
				(font
					(size 1.27 1.27)
					(thickness 0.15)
				)
				(justify left bottom)
				(hide yes)
			)
		)
		(property "Manufacturer" "Panasonic"
			(at 120.65 155.575 0)
			(effects
				(font
					(size 1.27 1.27)
					(thickness 0.15)
				)
				(justify left bottom)
				(hide yes)
			)
		)
		(property "Author" "Antmicro"
			(at 120.65 158.115 0)
			(effects
				(font
					(size 1.27 1.27)
					(thickness 0.15)
				)
				(justify left bottom)
				(hide yes)
			)
		)
		(property "License" "Apache-2.0"
			(at 120.65 160.655 0)
			(effects
				(font
					(size 1.27 1.27)
					(thickness 0.15)
				)
				(justify left bottom)
				(hide yes)
			)
		)
		(property "Val" "R_4x33R_0201"
			(at 120.65 145.415 0)
			(effects
				(font
					(size 1.27 1.27)
				)
				(justify left bottom)
				(hide yes)
			)
		)
		(pin "1"
		)
		(pin "2"
		)
		(pin "3"
		)
		(pin "4"
		)
		(pin "5"
		)
		(pin "6"
		)
		(pin "7"
		)
		(pin "8"
		)
		(instances
			(project "k410t-devboard"
				(path ""
					(reference "R21")
					(unit 1)
				)
			)
		)
	)
	(symbol
		(lib_id "antmicroResistorNetworksArrays:R_4x33R_0201_array")
		(at 168.91 124.46 0)
		(unit 1)
		(exclude_from_sim no)
		(in_bom yes)
		(on_board yes)
		(dnp no)
		(property "Reference" "R25"
			(at 173.99 104.14 0)
			(effects
				(font
					(size 1.27 1.27)
				)
			)
		)
		(property "Value" "R_4x33R_0201_array"
			(at 195.58 130.175 0)
			(effects
				(font
					(size 1.27 1.27)
					(thickness 0.15)
				)
				(justify left bottom)
				(hide yes)
			)
		)
		(property "Footprint" "antmicro-footprints:R_Array_4x0201_Panasonic_EXB18V"
			(at 195.58 135.255 0)
			(effects
				(font
					(size 1.27 1.27)
					(thickness 0.15)
				)
				(justify left bottom)
				(hide yes)
			)
		)
		(property "Datasheet" "http://industrial.panasonic.com/cdbs/www-data/pdf/AOC0000/AOC0000C14.pdf"
			(at 195.58 137.795 0)
			(effects
				(font
					(size 1.27 1.27)
					(thickness 0.15)
				)
				(justify left bottom)
				(hide yes)
			)
		)
		(property "Description" ""
			(at 168.91 124.46 0)
			(effects
				(font
					(size 1.27 1.27)
				)
			)
		)
		(property "MPN" "EXB-18V330JX"
			(at 195.58 140.335 0)
			(effects
				(font
					(size 1.27 1.27)
					(thickness 0.15)
				)
				(justify left bottom)
				(hide yes)
			)
		)
		(property "Manufacturer" "Panasonic"
			(at 195.58 142.875 0)
			(effects
				(font
					(size 1.27 1.27)
					(thickness 0.15)
				)
				(justify left bottom)
				(hide yes)
			)
		)
		(property "Author" "Antmicro"
			(at 195.58 145.415 0)
			(effects
				(font
					(size 1.27 1.27)
					(thickness 0.15)
				)
				(justify left bottom)
				(hide yes)
			)
		)
		(property "License" "Apache-2.0"
			(at 195.58 147.955 0)
			(effects
				(font
					(size 1.27 1.27)
					(thickness 0.15)
				)
				(justify left bottom)
				(hide yes)
			)
		)
		(property "Val" "R_4x33R_0201"
			(at 195.58 132.715 0)
			(effects
				(font
					(size 1.27 1.27)
				)
				(justify left bottom)
				(hide yes)
			)
		)
		(pin "1"
		)
		(pin "2"
		)
		(pin "3"
		)
		(pin "4"
		)
		(pin "5"
		)
		(pin "6"
		)
		(pin "7"
		)
		(pin "8"
		)
		(instances
			(project "k410t-devboard"
				(path ""
					(reference "R25")
					(unit 1)
				)
			)
		)
	)
	(symbol
		(lib_id "antmicroResistorNetworksArrays:R_4x33R_0201_array")
		(at 248.92 157.48 0)
		(unit 1)
		(exclude_from_sim no)
		(in_bom yes)
		(on_board yes)
		(dnp no)
		(property "Reference" "R33"
			(at 254 110.49 0)
			(effects
				(font
					(size 1.27 1.27)
				)
			)
		)
		(property "Value" "R_4x33R_0201_array"
			(at 254 171.45 0)
			(effects
				(font
					(size 1.27 1.27)
					(thickness 0.15)
				)
				(hide yes)
			)
		)
		(property "Footprint" "antmicro-footprints:R_Array_4x0201_Panasonic_EXB18V"
			(at 275.59 168.275 0)
			(effects
				(font
					(size 1.27 1.27)
					(thickness 0.15)
				)
				(justify left bottom)
				(hide yes)
			)
		)
		(property "Datasheet" "http://industrial.panasonic.com/cdbs/www-data/pdf/AOC0000/AOC0000C14.pdf"
			(at 275.59 170.815 0)
			(effects
				(font
					(size 1.27 1.27)
					(thickness 0.15)
				)
				(justify left bottom)
				(hide yes)
			)
		)
		(property "Description" ""
			(at 248.92 157.48 0)
			(effects
				(font
					(size 1.27 1.27)
				)
			)
		)
		(property "MPN" "EXB-18V330JX"
			(at 275.59 173.355 0)
			(effects
				(font
					(size 1.27 1.27)
					(thickness 0.15)
				)
				(justify left bottom)
				(hide yes)
			)
		)
		(property "Manufacturer" "Panasonic"
			(at 275.59 175.895 0)
			(effects
				(font
					(size 1.27 1.27)
					(thickness 0.15)
				)
				(justify left bottom)
				(hide yes)
			)
		)
		(property "Author" "Antmicro"
			(at 275.59 178.435 0)
			(effects
				(font
					(size 1.27 1.27)
					(thickness 0.15)
				)
				(justify left bottom)
				(hide yes)
			)
		)
		(property "License" "Apache-2.0"
			(at 275.59 180.975 0)
			(effects
				(font
					(size 1.27 1.27)
					(thickness 0.15)
				)
				(justify left bottom)
				(hide yes)
			)
		)
		(property "Val" "R_4x33R_0201"
			(at 254 171.45 0)
			(effects
				(font
					(size 1.27 1.27)
				)
				(hide yes)
			)
		)
		(pin "1"
		)
		(pin "2"
		)
		(pin "3"
		)
		(pin "4"
		)
		(pin "5"
		)
		(pin "6"
		)
		(pin "7"
		)
		(pin "8"
		)
		(instances
			(project "k410t-devboard"
				(path ""
					(reference "R33")
					(unit 1)
				)
			)
		)
	)
	(symbol
		(lib_id "antmicroResistorNetworksArrays:R_4x33R_0201_array")
		(at 322.58 147.32 0)
		(unit 1)
		(exclude_from_sim no)
		(in_bom yes)
		(on_board yes)
		(dnp no)
		(property "Reference" "R281"
			(at 327.66 108.7666 0)
			(effects
				(font
					(size 1.27 1.27)
				)
			)
		)
		(property "Value" "R_4x33R_0201_array"
			(at 349.25 153.035 0)
			(effects
				(font
					(size 1.27 1.27)
					(thickness 0.15)
				)
				(justify left bottom)
				(hide yes)
			)
		)
		(property "Footprint" "antmicro-footprints:R_Array_4x0201_Panasonic_EXB18V"
			(at 349.25 158.115 0)
			(effects
				(font
					(size 1.27 1.27)
					(thickness 0.15)
				)
				(justify left bottom)
				(hide yes)
			)
		)
		(property "Datasheet" "http://industrial.panasonic.com/cdbs/www-data/pdf/AOC0000/AOC0000C14.pdf"
			(at 349.25 160.655 0)
			(effects
				(font
					(size 1.27 1.27)
					(thickness 0.15)
				)
				(justify left bottom)
				(hide yes)
			)
		)
		(property "Description" ""
			(at 322.58 147.32 0)
			(effects
				(font
					(size 1.27 1.27)
				)
			)
		)
		(property "MPN" "EXB-18V330JX"
			(at 349.25 163.195 0)
			(effects
				(font
					(size 1.27 1.27)
					(thickness 0.15)
				)
				(justify left bottom)
				(hide yes)
			)
		)
		(property "Manufacturer" "Panasonic"
			(at 349.25 165.735 0)
			(effects
				(font
					(size 1.27 1.27)
					(thickness 0.15)
				)
				(justify left bottom)
				(hide yes)
			)
		)
		(property "Author" "Antmicro"
			(at 349.25 168.275 0)
			(effects
				(font
					(size 1.27 1.27)
					(thickness 0.15)
				)
				(justify left bottom)
				(hide yes)
			)
		)
		(property "License" "Apache-2.0"
			(at 349.25 170.815 0)
			(effects
				(font
					(size 1.27 1.27)
					(thickness 0.15)
				)
				(justify left bottom)
				(hide yes)
			)
		)
		(property "Val" "R_4x33R_0201"
			(at 349.25 155.575 0)
			(effects
				(font
					(size 1.27 1.27)
				)
				(justify left bottom)
				(hide yes)
			)
		)
		(pin "1"
		)
		(pin "2"
		)
		(pin "3"
		)
		(pin "4"
		)
		(pin "5"
		)
		(pin "6"
		)
		(pin "7"
		)
		(pin "8"
		)
		(instances
			(project "k410t-devboard"
				(path ""
					(reference "R281")
					(unit 1)
				)
			)
		)
	)
	(symbol
		(lib_id "antmicroResistorNetworksArrays:R_4x33R_0201_array")
		(at 93.98 127 0)
		(unit 1)
		(exclude_from_sim no)
		(in_bom yes)
		(on_board yes)
		(dnp no)
		(property "Reference" "R20"
			(at 99.06 114.935 0)
			(effects
				(font
					(size 1.27 1.27)
				)
			)
		)
		(property "Value" "R_4x33R_0201_array"
			(at 120.65 132.715 0)
			(effects
				(font
					(size 1.27 1.27)
					(thickness 0.15)
				)
				(justify left bottom)
				(hide yes)
			)
		)
		(property "Footprint" "antmicro-footprints:R_Array_4x0201_Panasonic_EXB18V"
			(at 120.65 137.795 0)
			(effects
				(font
					(size 1.27 1.27)
					(thickness 0.15)
				)
				(justify left bottom)
				(hide yes)
			)
		)
		(property "Datasheet" "http://industrial.panasonic.com/cdbs/www-data/pdf/AOC0000/AOC0000C14.pdf"
			(at 120.65 140.335 0)
			(effects
				(font
					(size 1.27 1.27)
					(thickness 0.15)
				)
				(justify left bottom)
				(hide yes)
			)
		)
		(property "Description" ""
			(at 93.98 127 0)
			(effects
				(font
					(size 1.27 1.27)
				)
			)
		)
		(property "MPN" "EXB-18V330JX"
			(at 120.65 142.875 0)
			(effects
				(font
					(size 1.27 1.27)
					(thickness 0.15)
				)
				(justify left bottom)
				(hide yes)
			)
		)
		(property "Manufacturer" "Panasonic"
			(at 120.65 145.415 0)
			(effects
				(font
					(size 1.27 1.27)
					(thickness 0.15)
				)
				(justify left bottom)
				(hide yes)
			)
		)
		(property "Author" "Antmicro"
			(at 120.65 147.955 0)
			(effects
				(font
					(size 1.27 1.27)
					(thickness 0.15)
				)
				(justify left bottom)
				(hide yes)
			)
		)
		(property "License" "Apache-2.0"
			(at 120.65 150.495 0)
			(effects
				(font
					(size 1.27 1.27)
					(thickness 0.15)
				)
				(justify left bottom)
				(hide yes)
			)
		)
		(property "Val" "R_4x33R_0201"
			(at 99.06 123.825 0)
			(effects
				(font
					(size 1.27 1.27)
				)
			)
		)
		(pin "1"
		)
		(pin "2"
		)
		(pin "3"
		)
		(pin "4"
		)
		(pin "5"
		)
		(pin "6"
		)
		(pin "7"
		)
		(pin "8"
		)
		(instances
			(project "k410t-devboard"
				(path ""
					(reference "R20")
					(unit 1)
				)
			)
		)
	)
	(symbol
		(lib_id "antmicroResistorNetworksArrays:R_4x33R_0201_array")
		(at 168.91 134.62 0)
		(unit 1)
		(exclude_from_sim no)
		(in_bom yes)
		(on_board yes)
		(dnp no)
		(property "Reference" "R26"
			(at 173.99 106.045 0)
			(effects
				(font
					(size 1.27 1.27)
				)
			)
		)
		(property "Value" "R_4x33R_0201_array"
			(at 195.58 140.335 0)
			(effects
				(font
					(size 1.27 1.27)
					(thickness 0.15)
				)
				(justify left bottom)
				(hide yes)
			)
		)
		(property "Footprint" "antmicro-footprints:R_Array_4x0201_Panasonic_EXB18V"
			(at 195.58 145.415 0)
			(effects
				(font
					(size 1.27 1.27)
					(thickness 0.15)
				)
				(justify left bottom)
				(hide yes)
			)
		)
		(property "Datasheet" "http://industrial.panasonic.com/cdbs/www-data/pdf/AOC0000/AOC0000C14.pdf"
			(at 195.58 147.955 0)
			(effects
				(font
					(size 1.27 1.27)
					(thickness 0.15)
				)
				(justify left bottom)
				(hide yes)
			)
		)
		(property "Description" ""
			(at 168.91 134.62 0)
			(effects
				(font
					(size 1.27 1.27)
				)
			)
		)
		(property "MPN" "EXB-18V330JX"
			(at 195.58 150.495 0)
			(effects
				(font
					(size 1.27 1.27)
					(thickness 0.15)
				)
				(justify left bottom)
				(hide yes)
			)
		)
		(property "Manufacturer" "Panasonic"
			(at 195.58 153.035 0)
			(effects
				(font
					(size 1.27 1.27)
					(thickness 0.15)
				)
				(justify left bottom)
				(hide yes)
			)
		)
		(property "Author" "Antmicro"
			(at 195.58 155.575 0)
			(effects
				(font
					(size 1.27 1.27)
					(thickness 0.15)
				)
				(justify left bottom)
				(hide yes)
			)
		)
		(property "License" "Apache-2.0"
			(at 195.58 158.115 0)
			(effects
				(font
					(size 1.27 1.27)
					(thickness 0.15)
				)
				(justify left bottom)
				(hide yes)
			)
		)
		(property "Val" "R_4x33R_0201"
			(at 195.58 142.875 0)
			(effects
				(font
					(size 1.27 1.27)
				)
				(justify left bottom)
				(hide yes)
			)
		)
		(pin "1"
		)
		(pin "2"
		)
		(pin "3"
		)
		(pin "4"
		)
		(pin "5"
		)
		(pin "6"
		)
		(pin "7"
		)
		(pin "8"
		)
		(instances
			(project "k410t-devboard"
				(path ""
					(reference "R26")
					(unit 1)
				)
			)
		)
	)
	(symbol
		(lib_id "antmicroResistorNetworksArrays:R_4x33R_0201_array")
		(at 248.92 147.32 0)
		(unit 1)
		(exclude_from_sim no)
		(in_bom yes)
		(on_board yes)
		(dnp no)
		(property "Reference" "R31"
			(at 254 108.585 0)
			(effects
				(font
					(size 1.27 1.27)
				)
			)
		)
		(property "Value" "R_4x33R_0201_array"
			(at 254 161.29 0)
			(effects
				(font
					(size 1.27 1.27)
					(thickness 0.15)
				)
				(hide yes)
			)
		)
		(property "Footprint" "antmicro-footprints:R_Array_4x0201_Panasonic_EXB18V"
			(at 275.59 158.115 0)
			(effects
				(font
					(size 1.27 1.27)
					(thickness 0.15)
				)
				(justify left bottom)
				(hide yes)
			)
		)
		(property "Datasheet" "http://industrial.panasonic.com/cdbs/www-data/pdf/AOC0000/AOC0000C14.pdf"
			(at 275.59 160.655 0)
			(effects
				(font
					(size 1.27 1.27)
					(thickness 0.15)
				)
				(justify left bottom)
				(hide yes)
			)
		)
		(property "Description" ""
			(at 248.92 147.32 0)
			(effects
				(font
					(size 1.27 1.27)
				)
			)
		)
		(property "MPN" "EXB-18V330JX"
			(at 275.59 163.195 0)
			(effects
				(font
					(size 1.27 1.27)
					(thickness 0.15)
				)
				(justify left bottom)
				(hide yes)
			)
		)
		(property "Manufacturer" "Panasonic"
			(at 275.59 165.735 0)
			(effects
				(font
					(size 1.27 1.27)
					(thickness 0.15)
				)
				(justify left bottom)
				(hide yes)
			)
		)
		(property "Author" "Antmicro"
			(at 275.59 168.275 0)
			(effects
				(font
					(size 1.27 1.27)
					(thickness 0.15)
				)
				(justify left bottom)
				(hide yes)
			)
		)
		(property "License" "Apache-2.0"
			(at 275.59 170.815 0)
			(effects
				(font
					(size 1.27 1.27)
					(thickness 0.15)
				)
				(justify left bottom)
				(hide yes)
			)
		)
		(property "Val" "R_4x33R_0201"
			(at 254 161.29 0)
			(effects
				(font
					(size 1.27 1.27)
				)
				(hide yes)
			)
		)
		(pin "1"
		)
		(pin "2"
		)
		(pin "3"
		)
		(pin "4"
		)
		(pin "5"
		)
		(pin "6"
		)
		(pin "7"
		)
		(pin "8"
		)
		(instances
			(project "k410t-devboard"
				(path ""
					(reference "R31")
					(unit 1)
				)
			)
		)
	)
	(symbol
		(lib_id "antmicropower:GND")
		(at 278.13 115.57 0)
		(unit 1)
		(exclude_from_sim no)
		(in_bom yes)
		(on_board yes)
		(dnp no)
		(property "Reference" "#PWR0479"
			(at 278.13 121.92 0)
			(effects
				(font
					(size 1.27 1.27)
				)
				(hide yes)
			)
		)
		(property "Value" "GND"
			(at 278.13 119.38 0)
			(effects
				(font
					(size 1.27 1.27)
				)
			)
		)
		(property "Footprint" ""
			(at 287.02 123.19 0)
			(effects
				(font
					(size 1.27 1.27)
					(thickness 0.15)
				)
				(justify left bottom)
				(hide yes)
			)
		)
		(property "Datasheet" ""
			(at 287.02 128.27 0)
			(effects
				(font
					(size 1.27 1.27)
					(thickness 0.15)
				)
				(justify left bottom)
				(hide yes)
			)
		)
		(property "Description" ""
			(at 278.13 115.57 0)
			(effects
				(font
					(size 1.27 1.27)
				)
			)
		)
		(property "Author" "Antmicro"
			(at 287.02 123.19 0)
			(effects
				(font
					(size 1.27 1.27)
					(thickness 0.15)
				)
				(justify left bottom)
				(hide yes)
			)
		)
		(property "License" "Apache-2.0"
			(at 287.02 125.73 0)
			(effects
				(font
					(size 1.27 1.27)
					(thickness 0.15)
				)
				(justify left bottom)
				(hide yes)
			)
		)
		(pin "1"
		)
		(instances
			(project "k410t-devboard"
				(path ""
					(reference "#PWR0479")
					(unit 1)
				)
			)
		)
	)
	(symbol
		(lib_id "antmicropower:+5V")
		(at 149.86 165.1 0)
		(mirror y)
		(unit 1)
		(exclude_from_sim no)
		(in_bom yes)
		(on_board yes)
		(dnp no)
		(property "Reference" "#PWR0456"
			(at 149.86 168.91 0)
			(effects
				(font
					(size 1.27 1.27)
				)
				(hide yes)
			)
		)
		(property "Value" "+5V"
			(at 149.86 161.544 0)
			(effects
				(font
					(size 1.27 1.27)
				)
			)
		)
		(property "Footprint" ""
			(at 149.86 165.1 0)
			(effects
				(font
					(size 1.27 1.27)
				)
				(hide yes)
			)
		)
		(property "Datasheet" ""
			(at 149.86 165.1 0)
			(effects
				(font
					(size 1.27 1.27)
				)
				(hide yes)
			)
		)
		(property "Description" ""
			(at 149.86 165.1 0)
			(effects
				(font
					(size 1.27 1.27)
				)
			)
		)
		(property "Author" "Antmicro"
			(at 134.62 172.72 0)
			(effects
				(font
					(size 1.27 1.27)
					(thickness 0.15)
				)
				(justify left bottom)
				(hide yes)
			)
		)
		(property "License" "Apache-2.0"
			(at 134.62 175.26 0)
			(effects
				(font
					(size 1.27 1.27)
					(thickness 0.15)
				)
				(justify left bottom)
				(hide yes)
			)
		)
		(pin "1"
		)
		(instances
			(project "k410t-devboard"
				(path ""
					(reference "#PWR0456")
					(unit 1)
				)
			)
		)
	)
	(symbol
		(lib_id "antmicroResistorNetworksArrays:R_4x33R_0201_array")
		(at 322.58 157.48 0)
		(unit 1)
		(exclude_from_sim no)
		(in_bom yes)
		(on_board yes)
		(dnp no)
		(property "Reference" "R282"
			(at 327.66 110.49 0)
			(effects
				(font
					(size 1.27 1.27)
				)
			)
		)
		(property "Value" "R_4x33R_0201_array"
			(at 349.25 163.195 0)
			(effects
				(font
					(size 1.27 1.27)
					(thickness 0.15)
				)
				(justify left bottom)
				(hide yes)
			)
		)
		(property "Footprint" "antmicro-footprints:R_Array_4x0201_Panasonic_EXB18V"
			(at 349.25 168.275 0)
			(effects
				(font
					(size 1.27 1.27)
					(thickness 0.15)
				)
				(justify left bottom)
				(hide yes)
			)
		)
		(property "Datasheet" "http://industrial.panasonic.com/cdbs/www-data/pdf/AOC0000/AOC0000C14.pdf"
			(at 349.25 170.815 0)
			(effects
				(font
					(size 1.27 1.27)
					(thickness 0.15)
				)
				(justify left bottom)
				(hide yes)
			)
		)
		(property "Description" ""
			(at 322.58 157.48 0)
			(effects
				(font
					(size 1.27 1.27)
				)
			)
		)
		(property "MPN" "EXB-18V330JX"
			(at 349.25 173.355 0)
			(effects
				(font
					(size 1.27 1.27)
					(thickness 0.15)
				)
				(justify left bottom)
				(hide yes)
			)
		)
		(property "Manufacturer" "Panasonic"
			(at 349.25 175.895 0)
			(effects
				(font
					(size 1.27 1.27)
					(thickness 0.15)
				)
				(justify left bottom)
				(hide yes)
			)
		)
		(property "Author" "Antmicro"
			(at 349.25 178.435 0)
			(effects
				(font
					(size 1.27 1.27)
					(thickness 0.15)
				)
				(justify left bottom)
				(hide yes)
			)
		)
		(property "License" "Apache-2.0"
			(at 349.25 180.975 0)
			(effects
				(font
					(size 1.27 1.27)
					(thickness 0.15)
				)
				(justify left bottom)
				(hide yes)
			)
		)
		(property "Val" "R_4x33R_0201"
			(at 349.25 165.735 0)
			(effects
				(font
					(size 1.27 1.27)
				)
				(justify left bottom)
				(hide yes)
			)
		)
		(pin "1"
		)
		(pin "2"
		)
		(pin "3"
		)
		(pin "4"
		)
		(pin "5"
		)
		(pin "6"
		)
		(pin "7"
		)
		(pin "8"
		)
		(instances
			(project "k410t-devboard"
				(path ""
					(reference "R282")
					(unit 1)
				)
			)
		)
	)
	(symbol
		(lib_id "antmicroB2BConnectors:Socket_Samtec_ERF5_2x20_ERF5-020-05.0-L-DV-K-TR")
		(at 283.21 116.84 0)
		(unit 1)
		(exclude_from_sim no)
		(in_bom yes)
		(on_board yes)
		(dnp no)
		(fields_autoplaced yes)
		(property "Reference" "J22"
			(at 288.925 109.22 0)
			(effects
				(font
					(size 1.27 1.27)
					(thickness 0.15)
				)
			)
		)
		(property "Value" "Socket_Samtec_ERF5_2x20_ERF5-020-05.0-L-DV-K-TR"
			(at 309.88 121.92 0)
			(effects
				(font
					(size 1.27 1.27)
					(thickness 0.15)
				)
				(justify left bottom)
				(hide yes)
			)
		)
		(property "Footprint" "antmicro-footprints:Conn_Socket_Samtec_ERF5_2x20_ERF5-020-05.0-L-DV-K-TR"
			(at 309.88 124.46 0)
			(effects
				(font
					(size 1.27 1.27)
					(thickness 0.15)
				)
				(justify left bottom)
				(hide yes)
			)
		)
		(property "Datasheet" "https://suddendocs.samtec.com/productspecs/erm5-erf5.pdf?_gl=1*1g914su*_ga*MTE0MzExNjY4MC4xNjcyMTQ5NTUz*_ga_3KFNZC07WW*MTY3Mjg0NzY5Ny42LjEuMTY3Mjg0ODE3MS42MC4wLjA."
			(at 309.88 127 0)
			(effects
				(font
					(size 1.27 1.27)
					(thickness 0.15)
				)
				(justify left bottom)
				(hide yes)
			)
		)
		(property "Description" ""
			(at 283.21 116.84 0)
			(effects
				(font
					(size 1.27 1.27)
				)
			)
		)
		(property "MPN" "ERF5-020-05.0-L-DV-K-TR"
			(at 288.925 111.76 0)
			(effects
				(font
					(size 1.27 1.27)
					(thickness 0.15)
				)
			)
		)
		(property "Manufacturer" "Samtec"
			(at 309.88 129.54 0)
			(effects
				(font
					(size 1.27 1.27)
					(thickness 0.15)
				)
				(justify left bottom)
				(hide yes)
			)
		)
		(property "Author" "Antmicro"
			(at 309.88 134.62 0)
			(effects
				(font
					(size 1.27 1.27)
					(thickness 0.15)
				)
				(justify left bottom)
				(hide yes)
			)
		)
		(property "License" "Apache-2.0"
			(at 309.88 137.16 0)
			(effects
				(font
					(size 1.27 1.27)
					(thickness 0.15)
				)
				(justify left bottom)
				(hide yes)
			)
		)
		(property "Pitch" "0.5 mm"
			(at 309.88 132.08 0)
			(effects
				(font
					(size 1.27 1.27)
				)
				(justify left bottom)
				(hide yes)
			)
		)
		(pin "4"
		)
		(pin "38"
		)
		(pin "16"
		)
		(pin "8"
		)
		(pin "15"
		)
		(pin "7"
		)
		(pin "28"
		)
		(pin "11"
		)
		(pin "31"
		)
		(pin "10"
		)
		(pin "34"
		)
		(pin "32"
		)
		(pin "26"
		)
		(pin "17"
		)
		(pin "19"
		)
		(pin "3"
		)
		(pin "29"
		)
		(pin "33"
		)
		(pin "6"
		)
		(pin "21"
		)
		(pin "18"
		)
		(pin "36"
		)
		(pin "24"
		)
		(pin "13"
		)
		(pin "27"
		)
		(pin "9"
		)
		(pin "5"
		)
		(pin "12"
		)
		(pin "22"
		)
		(pin "25"
		)
		(pin "39"
		)
		(pin "40"
		)
		(pin "30"
		)
		(pin "14"
		)
		(pin "1"
		)
		(pin "23"
		)
		(pin "2"
		)
		(pin "20"
		)
		(pin "35"
		)
		(pin "37"
		)
		(instances
			(project "k410t-devboard"
				(path ""
					(reference "J22")
					(unit 1)
				)
			)
		)
	)
	(symbol
		(lib_id "antmicropower:GND")
		(at 125.73 118.11 0)
		(unit 1)
		(exclude_from_sim no)
		(in_bom yes)
		(on_board yes)
		(dnp no)
		(fields_autoplaced yes)
		(property "Reference" "#PWR0478"
			(at 125.73 124.46 0)
			(effects
				(font
					(size 1.27 1.27)
				)
				(hide yes)
			)
		)
		(property "Value" "GND"
			(at 125.73 121.92 0)
			(effects
				(font
					(size 1.27 1.27)
				)
			)
		)
		(property "Footprint" ""
			(at 134.62 125.73 0)
			(effects
				(font
					(size 1.27 1.27)
					(thickness 0.15)
				)
				(justify left bottom)
				(hide yes)
			)
		)
		(property "Datasheet" ""
			(at 134.62 130.81 0)
			(effects
				(font
					(size 1.27 1.27)
					(thickness 0.15)
				)
				(justify left bottom)
				(hide yes)
			)
		)
		(property "Description" ""
			(at 125.73 118.11 0)
			(effects
				(font
					(size 1.27 1.27)
				)
			)
		)
		(property "Author" "Antmicro"
			(at 134.62 125.73 0)
			(effects
				(font
					(size 1.27 1.27)
					(thickness 0.15)
				)
				(justify left bottom)
				(hide yes)
			)
		)
		(property "License" "Apache-2.0"
			(at 134.62 128.27 0)
			(effects
				(font
					(size 1.27 1.27)
					(thickness 0.15)
				)
				(justify left bottom)
				(hide yes)
			)
		)
		(pin "1"
		)
		(instances
			(project "k410t-devboard"
				(path ""
					(reference "#PWR0478")
					(unit 1)
				)
			)
		)
	)
	(symbol
		(lib_id "antmicroResistorNetworksArrays:R_4x33R_0201_array")
		(at 168.91 144.78 0)
		(unit 1)
		(exclude_from_sim no)
		(in_bom yes)
		(on_board yes)
		(dnp no)
		(property "Reference" "R27"
			(at 173.99 107.95 0)
			(effects
				(font
					(size 1.27 1.27)
				)
			)
		)
		(property "Value" "R_4x33R_0201_array"
			(at 195.58 150.495 0)
			(effects
				(font
					(size 1.27 1.27)
					(thickness 0.15)
				)
				(justify left bottom)
				(hide yes)
			)
		)
		(property "Footprint" "antmicro-footprints:R_Array_4x0201_Panasonic_EXB18V"
			(at 195.58 155.575 0)
			(effects
				(font
					(size 1.27 1.27)
					(thickness 0.15)
				)
				(justify left bottom)
				(hide yes)
			)
		)
		(property "Datasheet" "http://industrial.panasonic.com/cdbs/www-data/pdf/AOC0000/AOC0000C14.pdf"
			(at 195.58 158.115 0)
			(effects
				(font
					(size 1.27 1.27)
					(thickness 0.15)
				)
				(justify left bottom)
				(hide yes)
			)
		)
		(property "Description" ""
			(at 168.91 144.78 0)
			(effects
				(font
					(size 1.27 1.27)
				)
			)
		)
		(property "MPN" "EXB-18V330JX"
			(at 195.58 160.655 0)
			(effects
				(font
					(size 1.27 1.27)
					(thickness 0.15)
				)
				(justify left bottom)
				(hide yes)
			)
		)
		(property "Manufacturer" "Panasonic"
			(at 195.58 163.195 0)
			(effects
				(font
					(size 1.27 1.27)
					(thickness 0.15)
				)
				(justify left bottom)
				(hide yes)
			)
		)
		(property "Author" "Antmicro"
			(at 195.58 165.735 0)
			(effects
				(font
					(size 1.27 1.27)
					(thickness 0.15)
				)
				(justify left bottom)
				(hide yes)
			)
		)
		(property "License" "Apache-2.0"
			(at 195.58 168.275 0)
			(effects
				(font
					(size 1.27 1.27)
					(thickness 0.15)
				)
				(justify left bottom)
				(hide yes)
			)
		)
		(property "Val" "R_4x33R_0201"
			(at 195.58 153.035 0)
			(effects
				(font
					(size 1.27 1.27)
				)
				(justify left bottom)
				(hide yes)
			)
		)
		(pin "1"
		)
		(pin "2"
		)
		(pin "3"
		)
		(pin "4"
		)
		(pin "5"
		)
		(pin "6"
		)
		(pin "7"
		)
		(pin "8"
		)
		(instances
			(project "k410t-devboard"
				(path ""
					(reference "R27")
					(unit 1)
				)
			)
		)
	)
	(symbol
		(lib_id "antmicroResistorNetworksArrays:R_4x33R_0201_array")
		(at 322.58 116.84 0)
		(unit 1)
		(exclude_from_sim no)
		(in_bom yes)
		(on_board yes)
		(dnp no)
		(property "Reference" "R41"
			(at 327.66 103.0516 0)
			(effects
				(font
					(size 1.27 1.27)
				)
			)
		)
		(property "Value" "R_4x33R_0201_array"
			(at 349.25 122.555 0)
			(effects
				(font
					(size 1.27 1.27)
					(thickness 0.15)
				)
				(justify left bottom)
				(hide yes)
			)
		)
		(property "Footprint" "antmicro-footprints:R_Array_4x0201_Panasonic_EXB18V"
			(at 349.25 127.635 0)
			(effects
				(font
					(size 1.27 1.27)
					(thickness 0.15)
				)
				(justify left bottom)
				(hide yes)
			)
		)
		(property "Datasheet" "http://industrial.panasonic.com/cdbs/www-data/pdf/AOC0000/AOC0000C14.pdf"
			(at 349.25 130.175 0)
			(effects
				(font
					(size 1.27 1.27)
					(thickness 0.15)
				)
				(justify left bottom)
				(hide yes)
			)
		)
		(property "Description" ""
			(at 322.58 116.84 0)
			(effects
				(font
					(size 1.27 1.27)
				)
			)
		)
		(property "MPN" "EXB-18V330JX"
			(at 349.25 132.715 0)
			(effects
				(font
					(size 1.27 1.27)
					(thickness 0.15)
				)
				(justify left bottom)
				(hide yes)
			)
		)
		(property "Manufacturer" "Panasonic"
			(at 349.25 135.255 0)
			(effects
				(font
					(size 1.27 1.27)
					(thickness 0.15)
				)
				(justify left bottom)
				(hide yes)
			)
		)
		(property "Author" "Antmicro"
			(at 349.25 137.795 0)
			(effects
				(font
					(size 1.27 1.27)
					(thickness 0.15)
				)
				(justify left bottom)
				(hide yes)
			)
		)
		(property "License" "Apache-2.0"
			(at 349.25 140.335 0)
			(effects
				(font
					(size 1.27 1.27)
					(thickness 0.15)
				)
				(justify left bottom)
				(hide yes)
			)
		)
		(property "Val" "R_4x33R_0201"
			(at 327.66 113.665 0)
			(effects
				(font
					(size 1.27 1.27)
				)
			)
		)
		(pin "1"
		)
		(pin "2"
		)
		(pin "3"
		)
		(pin "4"
		)
		(pin "5"
		)
		(pin "6"
		)
		(pin "7"
		)
		(pin "8"
		)
		(instances
			(project "k410t-devboard"
				(path ""
					(reference "R41")
					(unit 1)
				)
			)
		)
	)
	(symbol
		(lib_id "antmicroResistorNetworksArrays:R_4x33R_0201_array")
		(at 248.92 116.84 0)
		(unit 1)
		(exclude_from_sim no)
		(in_bom yes)
		(on_board yes)
		(dnp no)
		(property "Reference" "R28"
			(at 254 102.87 0)
			(effects
				(font
					(size 1.27 1.27)
				)
			)
		)
		(property "Value" "R_4x33R_0201_array"
			(at 254 110.49 0)
			(effects
				(font
					(size 1.27 1.27)
					(thickness 0.15)
				)
				(hide yes)
			)
		)
		(property "Footprint" "antmicro-footprints:R_Array_4x0201_Panasonic_EXB18V"
			(at 275.59 127.635 0)
			(effects
				(font
					(size 1.27 1.27)
					(thickness 0.15)
				)
				(justify left bottom)
				(hide yes)
			)
		)
		(property "Datasheet" "http://industrial.panasonic.com/cdbs/www-data/pdf/AOC0000/AOC0000C14.pdf"
			(at 275.59 130.175 0)
			(effects
				(font
					(size 1.27 1.27)
					(thickness 0.15)
				)
				(justify left bottom)
				(hide yes)
			)
		)
		(property "Description" ""
			(at 248.92 116.84 0)
			(effects
				(font
					(size 1.27 1.27)
				)
			)
		)
		(property "MPN" "EXB-18V330JX"
			(at 275.59 132.715 0)
			(effects
				(font
					(size 1.27 1.27)
					(thickness 0.15)
				)
				(justify left bottom)
				(hide yes)
			)
		)
		(property "Manufacturer" "Panasonic"
			(at 275.59 135.255 0)
			(effects
				(font
					(size 1.27 1.27)
					(thickness 0.15)
				)
				(justify left bottom)
				(hide yes)
			)
		)
		(property "Author" "Antmicro"
			(at 275.59 137.795 0)
			(effects
				(font
					(size 1.27 1.27)
					(thickness 0.15)
				)
				(justify left bottom)
				(hide yes)
			)
		)
		(property "License" "Apache-2.0"
			(at 275.59 140.335 0)
			(effects
				(font
					(size 1.27 1.27)
					(thickness 0.15)
				)
				(justify left bottom)
				(hide yes)
			)
		)
		(property "Val" "R_4x33R_0201"
			(at 254 113.665 0)
			(effects
				(font
					(size 1.27 1.27)
				)
			)
		)
		(pin "1"
		)
		(pin "2"
		)
		(pin "3"
		)
		(pin "4"
		)
		(pin "5"
		)
		(pin "6"
		)
		(pin "7"
		)
		(pin "8"
		)
		(instances
			(project "k410t-devboard"
				(path ""
					(reference "R28")
					(unit 1)
				)
			)
		)
	)
	(symbol
		(lib_id "antmicroResistorNetworksArrays:R_4x33R_0201_array")
		(at 322.58 137.16 0)
		(unit 1)
		(exclude_from_sim no)
		(in_bom yes)
		(on_board yes)
		(dnp no)
		(property "Reference" "R44"
			(at 327.66 106.8616 0)
			(effects
				(font
					(size 1.27 1.27)
				)
			)
		)
		(property "Value" "R_4x33R_0201_array"
			(at 349.25 142.875 0)
			(effects
				(font
					(size 1.27 1.27)
					(thickness 0.15)
				)
				(justify left bottom)
				(hide yes)
			)
		)
		(property "Footprint" "antmicro-footprints:R_Array_4x0201_Panasonic_EXB18V"
			(at 349.25 147.955 0)
			(effects
				(font
					(size 1.27 1.27)
					(thickness 0.15)
				)
				(justify left bottom)
				(hide yes)
			)
		)
		(property "Datasheet" "http://industrial.panasonic.com/cdbs/www-data/pdf/AOC0000/AOC0000C14.pdf"
			(at 349.25 150.495 0)
			(effects
				(font
					(size 1.27 1.27)
					(thickness 0.15)
				)
				(justify left bottom)
				(hide yes)
			)
		)
		(property "Description" ""
			(at 322.58 137.16 0)
			(effects
				(font
					(size 1.27 1.27)
				)
			)
		)
		(property "MPN" "EXB-18V330JX"
			(at 349.25 153.035 0)
			(effects
				(font
					(size 1.27 1.27)
					(thickness 0.15)
				)
				(justify left bottom)
				(hide yes)
			)
		)
		(property "Manufacturer" "Panasonic"
			(at 349.25 155.575 0)
			(effects
				(font
					(size 1.27 1.27)
					(thickness 0.15)
				)
				(justify left bottom)
				(hide yes)
			)
		)
		(property "Author" "Antmicro"
			(at 349.25 158.115 0)
			(effects
				(font
					(size 1.27 1.27)
					(thickness 0.15)
				)
				(justify left bottom)
				(hide yes)
			)
		)
		(property "License" "Apache-2.0"
			(at 349.25 160.655 0)
			(effects
				(font
					(size 1.27 1.27)
					(thickness 0.15)
				)
				(justify left bottom)
				(hide yes)
			)
		)
		(property "Val" "R_4x33R_0201"
			(at 349.25 145.415 0)
			(effects
				(font
					(size 1.27 1.27)
				)
				(justify left bottom)
				(hide yes)
			)
		)
		(pin "1"
		)
		(pin "2"
		)
		(pin "3"
		)
		(pin "4"
		)
		(pin "5"
		)
		(pin "6"
		)
		(pin "7"
		)
		(pin "8"
		)
		(instances
			(project "k410t-devboard"
				(path ""
					(reference "R44")
					(unit 1)
				)
			)
		)
	)
	(symbol
		(lib_id "k410t-devboard:Net-Tie_2")
		(at 43.18 101.6 0)
		(mirror x)
		(unit 1)
		(exclude_from_sim no)
		(in_bom yes)
		(on_board yes)
		(dnp no)
		(fields_autoplaced yes)
		(property "Reference" "NT22"
			(at 43.18 102.87 0)
			(effects
				(font
					(size 1.27 1.27)
				)
				(hide yes)
			)
		)
		(property "Value" "Net-Tie_2"
			(at 64.77 99.06 0)
			(effects
				(font
					(size 1.27 1.27)
					(thickness 0.15)
				)
				(justify left bottom)
				(hide yes)
			)
		)
		(property "Footprint" "antmicro-footprints:NetTie-2_SMD_Pad0.127mm"
			(at 64.77 96.52 0)
			(effects
				(font
					(size 1.27 1.27)
					(thickness 0.15)
				)
				(justify left bottom)
				(hide yes)
			)
		)
		(property "Datasheet" ""
			(at 64.77 93.98 0)
			(effects
				(font
					(size 1.27 1.27)
					(thickness 0.15)
				)
				(justify left bottom)
				(hide yes)
			)
		)
		(property "Description" ""
			(at 43.18 101.6 0)
			(effects
				(font
					(size 1.27 1.27)
				)
			)
		)
		(property "MPN" ""
			(at 64.77 92.71 0)
			(effects
				(font
					(size 1.27 1.27)
				)
				(justify left)
				(hide yes)
			)
		)
		(property "Manufacturer" ""
			(at 64.77 90.17 0)
			(effects
				(font
					(size 1.27 1.27)
				)
				(justify left)
				(hide yes)
			)
		)
		(property "Author" "Antmicro"
			(at 64.77 86.36 0)
			(effects
				(font
					(size 1.27 1.27)
					(thickness 0.15)
				)
				(justify left bottom)
				(hide yes)
			)
		)
		(property "License" "Apache-2.0"
			(at 64.77 83.82 0)
			(effects
				(font
					(size 1.27 1.27)
					(thickness 0.15)
				)
				(justify left bottom)
				(hide yes)
			)
		)
		(pin "1"
		)
		(pin "2"
		)
		(instances
			(project "k410t-devboard"
				(path ""
					(reference "NT22")
					(unit 1)
				)
			)
		)
	)
	(symbol
		(lib_id "antmicroResistorNetworksArrays:R_4x33R_0201_array")
		(at 248.92 127 0)
		(unit 1)
		(exclude_from_sim no)
		(in_bom yes)
		(on_board yes)
		(dnp no)
		(property "Reference" "R29"
			(at 254 104.775 0)
			(effects
				(font
					(size 1.27 1.27)
				)
			)
		)
		(property "Value" "R_4x33R_0201_array"
			(at 275.59 132.715 0)
			(effects
				(font
					(size 1.27 1.27)
					(thickness 0.15)
				)
				(justify left bottom)
				(hide yes)
			)
		)
		(property "Footprint" "antmicro-footprints:R_Array_4x0201_Panasonic_EXB18V"
			(at 275.59 137.795 0)
			(effects
				(font
					(size 1.27 1.27)
					(thickness 0.15)
				)
				(justify left bottom)
				(hide yes)
			)
		)
		(property "Datasheet" "http://industrial.panasonic.com/cdbs/www-data/pdf/AOC0000/AOC0000C14.pdf"
			(at 275.59 140.335 0)
			(effects
				(font
					(size 1.27 1.27)
					(thickness 0.15)
				)
				(justify left bottom)
				(hide yes)
			)
		)
		(property "Description" ""
			(at 248.92 127 0)
			(effects
				(font
					(size 1.27 1.27)
				)
			)
		)
		(property "MPN" "EXB-18V330JX"
			(at 275.59 142.875 0)
			(effects
				(font
					(size 1.27 1.27)
					(thickness 0.15)
				)
				(justify left bottom)
				(hide yes)
			)
		)
		(property "Manufacturer" "Panasonic"
			(at 275.59 145.415 0)
			(effects
				(font
					(size 1.27 1.27)
					(thickness 0.15)
				)
				(justify left bottom)
				(hide yes)
			)
		)
		(property "Author" "Antmicro"
			(at 275.59 147.955 0)
			(effects
				(font
					(size 1.27 1.27)
					(thickness 0.15)
				)
				(justify left bottom)
				(hide yes)
			)
		)
		(property "License" "Apache-2.0"
			(at 275.59 150.495 0)
			(effects
				(font
					(size 1.27 1.27)
					(thickness 0.15)
				)
				(justify left bottom)
				(hide yes)
			)
		)
		(property "Val" "R_4x33R_0201"
			(at 254 123.19 0)
			(effects
				(font
					(size 1.27 1.27)
				)
				(hide yes)
			)
		)
		(pin "1"
		)
		(pin "2"
		)
		(pin "3"
		)
		(pin "4"
		)
		(pin "5"
		)
		(pin "6"
		)
		(pin "7"
		)
		(pin "8"
		)
		(instances
			(project "k410t-devboard"
				(path ""
					(reference "R29")
					(unit 1)
				)
			)
		)
	)
	(symbol
		(lib_id "k410t-devboard:Net-Tie_2")
		(at 43.18 104.14 0)
		(mirror x)
		(unit 1)
		(exclude_from_sim no)
		(in_bom yes)
		(on_board yes)
		(dnp no)
		(fields_autoplaced yes)
		(property "Reference" "NT23"
			(at 43.18 105.41 0)
			(effects
				(font
					(size 1.27 1.27)
				)
				(hide yes)
			)
		)
		(property "Value" "Net-Tie_2"
			(at 64.77 101.6 0)
			(effects
				(font
					(size 1.27 1.27)
					(thickness 0.15)
				)
				(justify left bottom)
				(hide yes)
			)
		)
		(property "Footprint" "antmicro-footprints:NetTie-2_SMD_Pad0.127mm"
			(at 64.77 99.06 0)
			(effects
				(font
					(size 1.27 1.27)
					(thickness 0.15)
				)
				(justify left bottom)
				(hide yes)
			)
		)
		(property "Datasheet" ""
			(at 64.77 96.52 0)
			(effects
				(font
					(size 1.27 1.27)
					(thickness 0.15)
				)
				(justify left bottom)
				(hide yes)
			)
		)
		(property "Description" ""
			(at 43.18 104.14 0)
			(effects
				(font
					(size 1.27 1.27)
				)
			)
		)
		(property "MPN" ""
			(at 64.77 95.25 0)
			(effects
				(font
					(size 1.27 1.27)
				)
				(justify left)
				(hide yes)
			)
		)
		(property "Manufacturer" ""
			(at 64.77 92.71 0)
			(effects
				(font
					(size 1.27 1.27)
				)
				(justify left)
				(hide yes)
			)
		)
		(property "Author" "Antmicro"
			(at 64.77 88.9 0)
			(effects
				(font
					(size 1.27 1.27)
					(thickness 0.15)
				)
				(justify left bottom)
				(hide yes)
			)
		)
		(property "License" "Apache-2.0"
			(at 64.77 86.36 0)
			(effects
				(font
					(size 1.27 1.27)
					(thickness 0.15)
				)
				(justify left bottom)
				(hide yes)
			)
		)
		(pin "1"
		)
		(pin "2"
		)
		(instances
			(project "k410t-devboard"
				(path ""
					(reference "NT23")
					(unit 1)
				)
			)
		)
	)
	(symbol
		(lib_id "antmicroResistorNetworksArrays:R_4x33R_0201_array")
		(at 93.98 147.32 0)
		(unit 1)
		(exclude_from_sim no)
		(in_bom yes)
		(on_board yes)
		(dnp no)
		(property "Reference" "R22"
			(at 99.06 118.745 0)
			(effects
				(font
					(size 1.27 1.27)
				)
			)
		)
		(property "Value" "R_4x33R_0201_array"
			(at 120.65 153.035 0)
			(effects
				(font
					(size 1.27 1.27)
					(thickness 0.15)
				)
				(justify left bottom)
				(hide yes)
			)
		)
		(property "Footprint" "antmicro-footprints:R_Array_4x0201_Panasonic_EXB18V"
			(at 120.65 158.115 0)
			(effects
				(font
					(size 1.27 1.27)
					(thickness 0.15)
				)
				(justify left bottom)
				(hide yes)
			)
		)
		(property "Datasheet" "http://industrial.panasonic.com/cdbs/www-data/pdf/AOC0000/AOC0000C14.pdf"
			(at 120.65 160.655 0)
			(effects
				(font
					(size 1.27 1.27)
					(thickness 0.15)
				)
				(justify left bottom)
				(hide yes)
			)
		)
		(property "Description" ""
			(at 93.98 147.32 0)
			(effects
				(font
					(size 1.27 1.27)
				)
			)
		)
		(property "MPN" "EXB-18V330JX"
			(at 120.65 163.195 0)
			(effects
				(font
					(size 1.27 1.27)
					(thickness 0.15)
				)
				(justify left bottom)
				(hide yes)
			)
		)
		(property "Manufacturer" "Panasonic"
			(at 120.65 165.735 0)
			(effects
				(font
					(size 1.27 1.27)
					(thickness 0.15)
				)
				(justify left bottom)
				(hide yes)
			)
		)
		(property "Author" "Antmicro"
			(at 120.65 168.275 0)
			(effects
				(font
					(size 1.27 1.27)
					(thickness 0.15)
				)
				(justify left bottom)
				(hide yes)
			)
		)
		(property "License" "Apache-2.0"
			(at 120.65 170.815 0)
			(effects
				(font
					(size 1.27 1.27)
					(thickness 0.15)
				)
				(justify left bottom)
				(hide yes)
			)
		)
		(property "Val" "R_4x33R_0201"
			(at 120.65 155.575 0)
			(effects
				(font
					(size 1.27 1.27)
				)
				(justify left bottom)
				(hide yes)
			)
		)
		(pin "1"
		)
		(pin "2"
		)
		(pin "3"
		)
		(pin "4"
		)
		(pin "5"
		)
		(pin "6"
		)
		(pin "7"
		)
		(pin "8"
		)
		(instances
			(project "k410t-devboard"
				(path ""
					(reference "R22")
					(unit 1)
				)
			)
		)
	)
)
